FILE_TYPE = MACRO_DRAWING;
SET COLOR_WIRE YELLOW;
SET COLOR_PROP ORANGE;
SET COLOR_DOT WHITE;
SET COLOR_ARC YELLOW;
SET COLOR_BODY GREEN;
SET COLOR_NOTE PURPLE;
SET PROP_DISPLAY VALUE;
SET PAGE_NUMBER P177;
FORCEADD UNIVERSAL_GND..1
(825 950);
FORCEPROP 3 LASTPIN (825 1000) SIG_NAME GND\g
J 0
(835 1010);
DISPLAY 0.659574 (835 1010);
PAINT MONO (835 1010);
DISPLAY INVISIBLE (835 1010);
FORCEPROP 2 LAST CDS_LIB pure_quanta_power
J 0
(825 950);
DISPLAY INVISIBLE (825 950);
FORCEPROP 1 LAST HDL_POWER GND
J 1
(850 875);
DISPLAY 0.872340 (850 875);
PAINT GREEN (850 875);
DISPLAY INVISIBLE (850 875);
FORCEPROP 1 LAST PATH I1
J 0
(900 950);
DISPLAY 0.872340 (900 950);
PAINT AQUA (900 950);
DISPLAY INVISIBLE (900 950);
FORCEADD OFFPAGE..5
(1800 1525);
FORCEPROP 2 LAST $XR0 200 
J 0
(1545 1525);
DISPLAY 0.638298 (1545 1525);
PAINT MONO (1545 1525);
FORCEPROP 2 LAST CDS_LIB standard
J 0
(1800 1525);
DISPLAY INVISIBLE (1800 1525);
FORCEPROP 1 LAST OFFPAGE TRUE
J 0
(2125 1400);
DISPLAY 0.872340 (2125 1400);
PAINT GREEN (2125 1400);
DISPLAY INVISIBLE (2125 1400);
FORCEPROP 1 LAST COMMENT_BODY TRUE
J 0
(1900 1450);
DISPLAY 0.872340 (1900 1450);
PAINT GREEN (1900 1450);
DISPLAY INVISIBLE (1900 1450);
FORCEPROP 2 LAST PATH I10
J 0
(1550 1575);
DISPLAY 0.680851 (1550 1575);
DISPLAY INVISIBLE (1550 1575);
FORCEADD UNIVERSAL_GND..1
(850 3775);
FORCEPROP 3 LASTPIN (850 3825) SIG_NAME GND\g
J 0
(860 3835);
DISPLAY 0.659574 (860 3835);
PAINT MONO (860 3835);
DISPLAY INVISIBLE (860 3835);
FORCEPROP 2 LAST CDS_LIB pure_quanta_power
J 0
(850 3775);
DISPLAY INVISIBLE (850 3775);
FORCEPROP 1 LAST HDL_POWER GND
J 1
(875 3700);
DISPLAY 0.872340 (875 3700);
PAINT GREEN (875 3700);
DISPLAY INVISIBLE (875 3700);
FORCEPROP 1 LAST PATH I11
J 0
(925 3775);
DISPLAY 0.872340 (925 3775);
PAINT AQUA (925 3775);
DISPLAY INVISIBLE (925 3775);
FORCEADD Q_CAP..1
(850 3975);
FORCEPROP 1 LAST LOCATION PC114_3
J 0
(900 4075);
DISPLAY 0.489362 (900 4075);
PAINT SKYBLUE (900 4075);
FORCEPROP 0 LAST $SEC 1
J 0
(900 4100);
DISPLAY 0.680851 (900 4100);
PAINT MONO (900 4100);
DISPLAY INVISIBLE (900 4100);
FORCEPROP 0 LAST CDS_SEC 1
J 0
(1100 4025);
DISPLAY 1.021277 (1100 4025);
DISPLAY INVISIBLE (1100 4025);
FORCEPROP 1 LASTPIN (850 4075) $PN 1
J 0
(860 4055);
DISPLAY 0.489362 (860 4055);
PAINT MONO (860 4055);
FORCEPROP 1 LASTPIN (850 3875) $PN 2
J 0
(860 3855);
DISPLAY 0.489362 (860 3855);
PAINT MONO (860 3855);
FORCEPROP 1 LAST PACK_TYPE 0402
J 0
(900 3775);
DISPLAY 0.489362 (900 3775);
PAINT SKYBLUE (900 3775);
FORCEPROP 1 LAST VOLTAGE 25V
J 0
(900 3975);
DISPLAY 0.489362 (900 3975);
PAINT SKYBLUE (900 3975);
FORCEPROP 1 LAST VALUE 0.1UF
J 0
(900 4025);
DISPLAY 0.489362 (900 4025);
PAINT SKYBLUE (900 4025);
FORCEPROP 1 LAST TOLERANCE 10%
J 0
(900 3925);
DISPLAY 0.489362 (900 3925);
PAINT SKYBLUE (900 3925);
FORCEPROP 1 LAST MATERIAL X7R
J 0
(900 3875);
DISPLAY 0.489362 (900 3875);
PAINT SKYBLUE (900 3875);
FORCEPROP 2 LAST CDS_LIB pure_quanta
J 0
(850 3975);
DISPLAY INVISIBLE (850 3975);
FORCEPROP 1 LAST PATH I12
J 0
(900 4125);
DISPLAY 0.978723 (900 4125);
PAINT WHITE (900 4125);
DISPLAY INVISIBLE (900 4125);
FORCEPROP 1 LAST PART_NUMBER CH4104K1B00
J 0
(900 3825);
DISPLAY 0.489362 (900 3825);
PAINT SKYBLUE (900 3825);
DISPLAY INVISIBLE (900 3825);
FORCEADD Q_RES..2
(1475 2525);
FORCEPROP 1 LAST LOCATION PR87
J 0
(1520 2650);
DISPLAY 0.489362 (1520 2650);
PAINT SKYBLUE (1520 2650);
FORCEPROP 0 LAST $SEC 1
J 0
(1525 2700);
DISPLAY 0.680851 (1525 2700);
PAINT MONO (1525 2700);
DISPLAY INVISIBLE (1525 2700);
FORCEPROP 0 LAST CDS_SEC 1
J 0
(1525 2700);
DISPLAY 1.021277 (1525 2700);
DISPLAY INVISIBLE (1525 2700);
FORCEPROP 1 LASTPIN (1475 2625) $PN 1
J 0
(1480 2587);
DISPLAY 0.489362 (1480 2587);
PAINT MONO (1480 2587);
FORCEPROP 1 LASTPIN (1475 2425) $PN 2
J 0
(1480 2435);
DISPLAY 0.489362 (1480 2435);
PAINT MONO (1480 2435);
FORCEPROP 1 LAST WATTAGE 1/16W
J 0
(1525 2500);
DISPLAY 0.489362 (1525 2500);
PAINT SKYBLUE (1525 2500);
FORCEPROP 1 LAST MATERIAL CHIP
J 0
(1525 2450);
DISPLAY 0.489362 (1525 2450);
PAINT SKYBLUE (1525 2450);
FORCEPROP 1 LAST TOLERANCE 1%
J 0
(1525 2550);
DISPLAY 0.489362 (1525 2550);
PAINT SKYBLUE (1525 2550);
FORCEPROP 1 LAST VALUE 2.2
J 0
(1525 2600);
DISPLAY 0.489362 (1525 2600);
PAINT SKYBLUE (1525 2600);
FORCEPROP 1 LAST PACK_TYPE 0402LF
J 0
(1525 2350);
DISPLAY 0.489362 (1525 2350);
PAINT SKYBLUE (1525 2350);
FORCEPROP 2 LAST CDS_LIB pure_quanta
J 0
(1475 2525);
DISPLAY INVISIBLE (1475 2525);
FORCEPROP 1 LAST PATH I13
J 0
(1525 2700);
DISPLAY 0.978723 (1525 2700);
PAINT WHITE (1525 2700);
DISPLAY INVISIBLE (1525 2700);
FORCEPROP 1 LAST PART_NUMBER CS-2202FB01
J 0
(1525 2400);
DISPLAY 0.489362 (1525 2400);
PAINT SKYBLUE (1525 2400);
DISPLAY INVISIBLE (1525 2400);
FORCEADD VCC_CORE..1
(1475 2950);
FORCEPROP 3 LASTPIN (1475 2900) SIG_NAME PVDDCR_CPU1_P0_PVCC\g
J 0
(1485 2910);
DISPLAY 0.659574 (1485 2910);
PAINT MONO (1485 2910);
DISPLAY INVISIBLE (1485 2910);
FORCEPROP 1 LAST HDL_POWER PVDDCR_CPU1_P0_PVCC
J 1
(1475 3000);
DISPLAY 0.489362 (1475 3000);
PAINT GREEN (1475 3000);
FORCEPROP 2 LAST CDS_LIB pure_quanta_power
J 0
(1475 2950);
DISPLAY INVISIBLE (1475 2950);
FORCEPROP 1 LAST PATH I14
J 0
(1525 2975);
DISPLAY 0.872340 (1525 2975);
PAINT AQUA (1525 2975);
DISPLAY INVISIBLE (1525 2975);
FORCEADD UNIVERSAL_GND..1
(1825 2275);
FORCEPROP 3 LASTPIN (1825 2325) SIG_NAME GND\g
J 0
(1835 2335);
DISPLAY 0.659574 (1835 2335);
PAINT MONO (1835 2335);
DISPLAY INVISIBLE (1835 2335);
FORCEPROP 2 LAST CDS_LIB pure_quanta_power
J 0
(1825 2275);
DISPLAY INVISIBLE (1825 2275);
FORCEPROP 1 LAST HDL_POWER GND
J 1
(1850 2200);
DISPLAY 0.872340 (1850 2200);
PAINT GREEN (1850 2200);
DISPLAY INVISIBLE (1850 2200);
FORCEPROP 1 LAST PATH I15
J 0
(1900 2275);
DISPLAY 0.872340 (1900 2275);
PAINT AQUA (1900 2275);
DISPLAY INVISIBLE (1900 2275);
FORCEADD Q_CAP..1
(1825 2550);
FORCEPROP 1 LAST LOCATION PC111_C1P0_4
J 0
(1875 2650);
DISPLAY 0.489362 (1875 2650);
PAINT SKYBLUE (1875 2650);
FORCEPROP 0 LAST $SEC 1
J 0
(1875 2700);
DISPLAY 0.680851 (1875 2700);
PAINT MONO (1875 2700);
DISPLAY INVISIBLE (1875 2700);
FORCEPROP 0 LAST CDS_SEC 1
J 0
(1875 2700);
DISPLAY 1.021277 (1875 2700);
DISPLAY INVISIBLE (1875 2700);
FORCEPROP 1 LASTPIN (1825 2650) $PN 1
J 0
(1835 2630);
DISPLAY 0.489362 (1835 2630);
PAINT MONO (1835 2630);
FORCEPROP 1 LASTPIN (1825 2450) $PN 2
J 0
(1835 2430);
DISPLAY 0.489362 (1835 2430);
PAINT MONO (1835 2430);
FORCEPROP 1 LAST PACK_TYPE C0402
J 0
(1875 2350);
DISPLAY 0.489362 (1875 2350);
PAINT SKYBLUE (1875 2350);
FORCEPROP 1 LAST VOLTAGE 10V
J 0
(1875 2550);
DISPLAY 0.489362 (1875 2550);
PAINT SKYBLUE (1875 2550);
FORCEPROP 1 LAST VALUE 2.2UF
J 0
(1875 2600);
DISPLAY 0.489362 (1875 2600);
PAINT SKYBLUE (1875 2600);
FORCEPROP 1 LAST TOLERANCE 10%
J 0
(1875 2500);
DISPLAY 0.489362 (1875 2500);
PAINT SKYBLUE (1875 2500);
FORCEPROP 1 LAST MATERIAL X6S
J 0
(1875 2450);
DISPLAY 0.489362 (1875 2450);
PAINT SKYBLUE (1875 2450);
FORCEPROP 2 LAST CDS_LIB pure_quanta
J 0
(1825 2550);
DISPLAY INVISIBLE (1825 2550);
FORCEPROP 1 LAST PATH I16
J 0
(1875 2700);
DISPLAY 0.978723 (1875 2700);
PAINT WHITE (1875 2700);
DISPLAY INVISIBLE (1875 2700);
FORCEPROP 1 LAST PART_NUMBER CH5222KEB01
J 0
(1875 2400);
DISPLAY 0.489362 (1875 2400);
PAINT SKYBLUE (1875 2400);
DISPLAY INVISIBLE (1875 2400);
FORCEADD UNIVERSAL_GND..1
(1350 3625);
FORCEPROP 3 LASTPIN (1350 3675) SIG_NAME GND\g
J 0
(1360 3685);
DISPLAY 0.659574 (1360 3685);
PAINT MONO (1360 3685);
DISPLAY INVISIBLE (1360 3685);
FORCEPROP 2 LAST CDS_LIB pure_quanta_power
J 0
(1350 3625);
PAINT MONO (1350 3625);
DISPLAY INVISIBLE (1350 3625);
FORCEPROP 1 LAST HDL_POWER GND
J 1
(1375 3550);
DISPLAY 0.872340 (1375 3550);
PAINT GREEN (1375 3550);
DISPLAY INVISIBLE (1375 3550);
FORCEPROP 1 LAST PATH I17
J 0
(1425 3625);
DISPLAY 0.872340 (1425 3625);
PAINT AQUA (1425 3625);
DISPLAY INVISIBLE (1425 3625);
FORCEADD Q_RES..2
R 2
(1350 3850);
FORCEPROP 1 LAST LOCATION PR86
J 2
(1305 3975);
DISPLAY 0.489362 (1305 3975);
PAINT SKYBLUE (1305 3975);
FORCEPROP 0 LAST $SEC 1
J 0
(1325 4025);
DISPLAY 0.680851 (1325 4025);
PAINT MONO (1325 4025);
DISPLAY INVISIBLE (1325 4025);
FORCEPROP 0 LAST CDS_SEC 1
J 0
(1325 4025);
DISPLAY 1.021277 (1325 4025);
DISPLAY INVISIBLE (1325 4025);
FORCEPROP 1 LASTPIN (1350 3950) $PN 1
J 2
(1345 3912);
DISPLAY 0.489362 (1345 3912);
PAINT MONO (1345 3912);
FORCEPROP 1 LASTPIN (1350 3750) $PN 2
J 2
(1345 3760);
DISPLAY 0.489362 (1345 3760);
PAINT MONO (1345 3760);
FORCEPROP 1 LAST WATTAGE 1/16W
J 2
(1310 3825);
DISPLAY 0.489362 (1310 3825);
PAINT SKYBLUE (1310 3825);
FORCEPROP 1 LAST MATERIAL EMPTY
J 2
(1310 3775);
DISPLAY 0.489362 (1310 3775);
PAINT RED (1310 3775);
FORCEPROP 1 LAST TOLERANCE 1%
J 2
(1305 3875);
DISPLAY 0.489362 (1305 3875);
PAINT SKYBLUE (1305 3875);
FORCEPROP 1 LAST VALUE 8.87K
J 2
(1305 3925);
DISPLAY 0.489362 (1305 3925);
PAINT SKYBLUE (1305 3925);
FORCEPROP 1 LAST PACK_TYPE 0402LF
J 2
(1310 3675);
DISPLAY 0.489362 (1310 3675);
PAINT SKYBLUE (1310 3675);
FORCEPROP 2 LAST CDS_LIB pure_quanta
J 2
(1350 3850);
DISPLAY INVISIBLE (1350 3850);
FORCEPROP 1 LAST PATH I18
J 2
(1300 4025);
DISPLAY 0.978723 (1300 4025);
PAINT WHITE (1300 4025);
DISPLAY INVISIBLE (1300 4025);
FORCEPROP 1 LAST PART_NUMBER CS28872FB01
J 2
(1310 3725);
DISPLAY 0.489362 (1310 3725);
PAINT SKYBLUE (1310 3725);
DISPLAY INVISIBLE (1310 3725);
FORCEADD OFFPAGE..1
(1825 3750);
FORCEPROP 2 LAST $XR0 200 
J 0
(1093 3750);
DISPLAY 0.638298 (1093 3750);
PAINT MONO (1093 3750);
FORCEPROP 2 LAST CDS_LIB standard
J 0
(1825 3750);
DISPLAY INVISIBLE (1825 3750);
FORCEPROP 1 LAST OFFPAGE TRUE
J 0
(2150 3625);
DISPLAY 0.872340 (2150 3625);
PAINT GREEN (2150 3625);
DISPLAY INVISIBLE (2150 3625);
FORCEPROP 1 LAST COMMENT_BODY TRUE
J 0
(1950 3650);
DISPLAY 0.872340 (1950 3650);
PAINT GREEN (1950 3650);
DISPLAY INVISIBLE (1950 3650);
FORCEPROP 2 LAST PATH I19
J 0
(1400 3800);
DISPLAY 0.680851 (1400 3800);
DISPLAY INVISIBLE (1400 3800);
FORCEADD Q_CAP..1
(825 1150);
FORCEPROP 1 LAST LOCATION PC113_4
J 0
(875 1250);
DISPLAY 0.489362 (875 1250);
PAINT SKYBLUE (875 1250);
FORCEPROP 0 LAST $SEC 1
J 0
(875 1275);
DISPLAY 0.680851 (875 1275);
PAINT MONO (875 1275);
DISPLAY INVISIBLE (875 1275);
FORCEPROP 0 LAST CDS_SEC 1
J 0
(1075 1200);
DISPLAY 1.021277 (1075 1200);
DISPLAY INVISIBLE (1075 1200);
FORCEPROP 1 LASTPIN (825 1250) $PN 1
J 0
(835 1230);
DISPLAY 0.489362 (835 1230);
PAINT MONO (835 1230);
FORCEPROP 1 LASTPIN (825 1050) $PN 2
J 0
(835 1030);
DISPLAY 0.489362 (835 1030);
PAINT MONO (835 1030);
FORCEPROP 1 LAST PACK_TYPE 0402
J 0
(875 950);
DISPLAY 0.489362 (875 950);
PAINT SKYBLUE (875 950);
FORCEPROP 1 LAST VOLTAGE 25V
J 0
(875 1150);
DISPLAY 0.489362 (875 1150);
PAINT SKYBLUE (875 1150);
FORCEPROP 1 LAST VALUE 0.1UF
J 0
(875 1200);
DISPLAY 0.489362 (875 1200);
PAINT SKYBLUE (875 1200);
FORCEPROP 1 LAST TOLERANCE 10%
J 0
(875 1100);
DISPLAY 0.489362 (875 1100);
PAINT SKYBLUE (875 1100);
FORCEPROP 1 LAST MATERIAL X7R
J 0
(875 1050);
DISPLAY 0.489362 (875 1050);
PAINT SKYBLUE (875 1050);
FORCEPROP 2 LAST CDS_LIB pure_quanta
J 0
(825 1150);
DISPLAY INVISIBLE (825 1150);
FORCEPROP 1 LAST PATH I2
J 0
(875 1300);
DISPLAY 0.978723 (875 1300);
PAINT WHITE (875 1300);
DISPLAY INVISIBLE (875 1300);
FORCEPROP 1 LAST PART_NUMBER CH4104K1B00
J 0
(875 1000);
DISPLAY 0.489362 (875 1000);
PAINT SKYBLUE (875 1000);
DISPLAY INVISIBLE (875 1000);
FORCEADD OFFPAGE..5
(1825 3850);
FORCEPROP 2 LAST $XR3 200 
J 0
(1540 3778);
DISPLAY 0.638298 (1540 3778);
PAINT MONO (1540 3778);
FORCEPROP 2 LAST $XR2 203 
J 0
(1540 3886);
DISPLAY 0.638298 (1540 3886);
PAINT MONO (1540 3886);
FORCEPROP 2 LAST $XR1 202 
J 0
(1540 3814);
DISPLAY 0.638298 (1540 3814);
PAINT MONO (1540 3814);
FORCEPROP 2 LAST $XR0 201 
J 0
(1540 3850);
DISPLAY 0.638298 (1540 3850);
PAINT MONO (1540 3850);
FORCEPROP 2 LAST CDS_LIB standard
J 0
(1825 3850);
DISPLAY INVISIBLE (1825 3850);
FORCEPROP 1 LAST OFFPAGE TRUE
J 0
(2150 3725);
DISPLAY 0.872340 (2150 3725);
PAINT GREEN (2150 3725);
DISPLAY INVISIBLE (2150 3725);
FORCEPROP 1 LAST COMMENT_BODY TRUE
J 0
(1925 3775);
DISPLAY 0.872340 (1925 3775);
PAINT GREEN (1925 3775);
DISPLAY INVISIBLE (1925 3775);
FORCEPROP 2 LAST PATH I20
J 0
(1575 3925);
DISPLAY 0.680851 (1575 3925);
DISPLAY INVISIBLE (1575 3925);
FORCEADD ISL99390FRZTR5935..1
(3250 1525);
FORCEPROP 1 LAST LOCATION PU14
J 0
(2950 2400);
DISPLAY 0.489362 (2950 2400);
PAINT SKYBLUE (2950 2400);
FORCEPROP 0 LAST $SEC 1
J 0
(2950 2600);
DISPLAY 0.680851 (2950 2600);
PAINT MONO (2950 2600);
DISPLAY INVISIBLE (2950 2600);
FORCEPROP 2 LAST CDS_SEC 1
J 0
(2950 2450);
DISPLAY 1.021277 (2950 2450);
DISPLAY INVISIBLE (2950 2450);
FORCEPROP 0 LASTPIN (3650 1075) $PN 2
J 0
(3660 1085);
DISPLAY 0.489362 (3660 1085);
PAINT MONO (3660 1085);
FORCEPROP 0 LASTPIN (3650 1875) $PN 33
J 0
(3660 1885);
DISPLAY 0.489362 (3660 1885);
PAINT MONO (3660 1885);
FORCEPROP 0 LASTPIN (2800 1275) $PN 31
J 2
(2790 1285);
DISPLAY 0.489362 (2790 1285);
PAINT MONO (2790 1285);
FORCEPROP 0 LASTPIN (2800 1675) $PN 35
J 2
(2790 1685);
DISPLAY 0.489362 (2790 1685);
PAINT MONO (2790 1685);
FORCEPROP 0 LASTPIN (3650 1225) $PN 6
J 0
(3660 1235);
DISPLAY 0.489362 (3660 1235);
PAINT MONO (3660 1235);
FORCEPROP 0 LASTPIN (3650 1175) $PN 41
J 0
(3660 1185);
DISPLAY 0.489362 (3660 1185);
PAINT MONO (3660 1185);
FORCEPROP 0 LASTPIN (2800 1525) $PN 38
J 2
(2790 1535);
DISPLAY 0.489362 (2790 1535);
PAINT MONO (2790 1535);
FORCEPROP 0 LASTPIN (2800 1225) $PN 37
J 2
(2790 1235);
DISPLAY 0.489362 (2790 1235);
PAINT MONO (2790 1235);
FORCEPROP 0 LASTPIN (3650 1025) $PN 5
J 0
(3660 1035);
DISPLAY 0.489362 (3660 1035);
PAINT MONO (3660 1035);
FORCEPROP 0 LASTPIN (3650 975) $PN 7_9-20_24
J 0
(3660 985);
DISPLAY 0.489362 (3660 985);
PAINT MONO (3660 985);
FORCEPROP 0 LASTPIN (3650 925) $PN 40
J 0
(3660 935);
DISPLAY 0.489362 (3660 935);
PAINT MONO (3660 935);
FORCEPROP 0 LASTPIN (3650 1625) $PN 32
J 0
(3660 1635);
DISPLAY 0.489362 (3660 1635);
PAINT MONO (3660 1635);
FORCEPROP 0 LASTPIN (2800 2175) $PN 4
J 2
(2790 2185);
DISPLAY 0.489362 (2790 2185);
PAINT MONO (2790 2185);
FORCEPROP 0 LASTPIN (2800 925) $PN 34
J 2
(2790 935);
DISPLAY 0.489362 (2790 935);
PAINT MONO (2790 935);
FORCEPROP 0 LASTPIN (2800 1425) $PN 39
J 2
(2790 1435);
DISPLAY 0.489362 (2790 1435);
PAINT MONO (2790 1435);
FORCEPROP 0 LASTPIN (3650 1525) $PN 10_19
J 0
(3660 1535);
DISPLAY 0.489362 (3660 1535);
PAINT MONO (3660 1535);
FORCEPROP 0 LASTPIN (2800 1025) $PN 36
J 2
(2790 1035);
DISPLAY 0.489362 (2790 1035);
PAINT MONO (2790 1035);
FORCEPROP 0 LASTPIN (2800 1875) $PN 3
J 2
(2790 1885);
DISPLAY 0.489362 (2790 1885);
PAINT MONO (2790 1885);
FORCEPROP 0 LASTPIN (3650 2175) $PN 25_29
J 0
(3660 2185);
DISPLAY 0.489362 (3660 2185);
PAINT MONO (3660 2185);
FORCEPROP 0 LASTPIN (3650 2125) $PN 30
J 0
(3660 2135);
DISPLAY 0.489362 (3660 2135);
PAINT MONO (3660 2135);
FORCEPROP 0 LASTPIN (3650 1275) $PN 1
J 0
(3660 1285);
DISPLAY 0.489362 (3660 1285);
PAINT MONO (3660 1285);
FORCEPROP 1 LAST MATERIAL IC
J 0
(2950 2250);
DISPLAY 0.489362 (2950 2250);
PAINT SKYBLUE (2950 2250);
FORCEPROP 2 LAST VALUE ISL99390FRZ-TR5935
J 0
(2950 2500);
DISPLAY 0.489362 (2950 2500);
PAINT SKYBLUE (2950 2500);
FORCEPROP 2 LAST PART_TYPE SMLF
J 0
(2950 2550);
DISPLAY 0.638298 (2950 2550);
FORCEPROP 2 LAST CDS_LIB pure_quanta
J 0
(3250 1525);
DISPLAY INVISIBLE (3250 1525);
FORCEPROP 1 LAST NEEDS_NO_SIZE TRUE
J 0
(3250 1525);
DISPLAY 0.723404 (3250 1525);
PAINT GREEN (3250 1525);
DISPLAY INVISIBLE (3250 1525);
FORCEPROP 1 LAST CDS_LMAN_SYM_OUTLINE -300,700,250,-650
J 0
(3250 1525);
DISPLAY 0.468085 (3250 1525);
PAINT GREEN (3250 1525);
DISPLAY INVISIBLE (3250 1525);
FORCEPROP 1 LAST PATH I21
J 0
(3250 1525);
DISPLAY 0.723404 (3250 1525);
PAINT GREEN (3250 1525);
DISPLAY INVISIBLE (3250 1525);
FORCEPROP 1 LAST PART_NUMBER AL099390004
J 0
(2950 2325);
DISPLAY 0.489362 (2950 2325);
PAINT SKYBLUE (2950 2325);
DISPLAY INVISIBLE (2950 2325);
FORCEADD UNIVERSAL_GND..1
(3900 800);
FORCEPROP 3 LASTPIN (3900 850) SIG_NAME GND\g
J 0
(3910 860);
DISPLAY 0.659574 (3910 860);
PAINT MONO (3910 860);
DISPLAY INVISIBLE (3910 860);
FORCEPROP 2 LAST CDS_LIB pure_quanta_power
J 0
(3900 800);
PAINT MONO (3900 800);
DISPLAY INVISIBLE (3900 800);
FORCEPROP 1 LAST HDL_POWER GND
J 1
(3925 725);
DISPLAY 0.872340 (3925 725);
PAINT GREEN (3925 725);
DISPLAY INVISIBLE (3925 725);
FORCEPROP 1 LAST PATH I22
J 0
(3975 800);
DISPLAY 0.872340 (3975 800);
PAINT AQUA (3975 800);
DISPLAY INVISIBLE (3975 800);
FORCEADD ISL99390FRZTR5935..1
(3275 4350);
FORCEPROP 1 LAST LOCATION PU15
J 0
(2975 5225);
DISPLAY 0.489362 (2975 5225);
PAINT SKYBLUE (2975 5225);
FORCEPROP 0 LAST $SEC 1
J 0
(2975 5425);
DISPLAY 0.680851 (2975 5425);
PAINT MONO (2975 5425);
DISPLAY INVISIBLE (2975 5425);
FORCEPROP 2 LAST CDS_SEC 1
J 0
(2975 5275);
DISPLAY 1.021277 (2975 5275);
DISPLAY INVISIBLE (2975 5275);
FORCEPROP 0 LASTPIN (3675 3900) $PN 2
J 0
(3685 3910);
DISPLAY 0.489362 (3685 3910);
PAINT MONO (3685 3910);
FORCEPROP 0 LASTPIN (3675 4700) $PN 33
J 0
(3685 4710);
DISPLAY 0.489362 (3685 4710);
PAINT MONO (3685 4710);
FORCEPROP 0 LASTPIN (2825 4100) $PN 31
J 2
(2815 4110);
DISPLAY 0.489362 (2815 4110);
PAINT MONO (2815 4110);
FORCEPROP 0 LASTPIN (2825 4500) $PN 35
J 2
(2815 4510);
DISPLAY 0.489362 (2815 4510);
PAINT MONO (2815 4510);
FORCEPROP 0 LASTPIN (3675 4050) $PN 6
J 0
(3685 4060);
DISPLAY 0.489362 (3685 4060);
PAINT MONO (3685 4060);
FORCEPROP 0 LASTPIN (3675 4000) $PN 41
J 0
(3685 4010);
DISPLAY 0.489362 (3685 4010);
PAINT MONO (3685 4010);
FORCEPROP 0 LASTPIN (2825 4350) $PN 38
J 2
(2815 4360);
DISPLAY 0.489362 (2815 4360);
PAINT MONO (2815 4360);
FORCEPROP 0 LASTPIN (2825 4050) $PN 37
J 2
(2815 4060);
DISPLAY 0.489362 (2815 4060);
PAINT MONO (2815 4060);
FORCEPROP 0 LASTPIN (3675 3850) $PN 5
J 0
(3685 3860);
DISPLAY 0.489362 (3685 3860);
PAINT MONO (3685 3860);
FORCEPROP 0 LASTPIN (3675 3800) $PN 7_9-20_24
J 0
(3685 3810);
DISPLAY 0.489362 (3685 3810);
PAINT MONO (3685 3810);
FORCEPROP 0 LASTPIN (3675 3750) $PN 40
J 0
(3685 3760);
DISPLAY 0.489362 (3685 3760);
PAINT MONO (3685 3760);
FORCEPROP 0 LASTPIN (3675 4450) $PN 32
J 0
(3685 4460);
DISPLAY 0.489362 (3685 4460);
PAINT MONO (3685 4460);
FORCEPROP 0 LASTPIN (2825 5000) $PN 4
J 2
(2815 5010);
DISPLAY 0.489362 (2815 5010);
PAINT MONO (2815 5010);
FORCEPROP 0 LASTPIN (2825 3750) $PN 34
J 2
(2815 3760);
DISPLAY 0.489362 (2815 3760);
PAINT MONO (2815 3760);
FORCEPROP 0 LASTPIN (2825 4250) $PN 39
J 2
(2815 4260);
DISPLAY 0.489362 (2815 4260);
PAINT MONO (2815 4260);
FORCEPROP 0 LASTPIN (3675 4350) $PN 10_19
J 0
(3685 4360);
DISPLAY 0.489362 (3685 4360);
PAINT MONO (3685 4360);
FORCEPROP 0 LASTPIN (2825 3850) $PN 36
J 2
(2815 3860);
DISPLAY 0.489362 (2815 3860);
PAINT MONO (2815 3860);
FORCEPROP 0 LASTPIN (2825 4700) $PN 3
J 2
(2815 4710);
DISPLAY 0.489362 (2815 4710);
PAINT MONO (2815 4710);
FORCEPROP 0 LASTPIN (3675 5000) $PN 25_29
J 0
(3685 5010);
DISPLAY 0.489362 (3685 5010);
PAINT MONO (3685 5010);
FORCEPROP 0 LASTPIN (3675 4950) $PN 30
J 0
(3685 4960);
DISPLAY 0.489362 (3685 4960);
PAINT MONO (3685 4960);
FORCEPROP 0 LASTPIN (3675 4100) $PN 1
J 0
(3685 4110);
DISPLAY 0.489362 (3685 4110);
PAINT MONO (3685 4110);
FORCEPROP 2 LAST VALUE ISL99390FRZ-TR5935
J 0
(2975 5325);
DISPLAY 0.489362 (2975 5325);
PAINT SKYBLUE (2975 5325);
FORCEPROP 1 LAST MATERIAL IC
J 0
(2975 5075);
DISPLAY 0.489362 (2975 5075);
PAINT SKYBLUE (2975 5075);
FORCEPROP 2 LAST PART_TYPE SMLF
J 0
(2975 5375);
DISPLAY 0.638298 (2975 5375);
FORCEPROP 2 LAST CDS_LIB pure_quanta
J 0
(3275 4350);
DISPLAY INVISIBLE (3275 4350);
FORCEPROP 1 LAST NEEDS_NO_SIZE TRUE
J 0
(3275 4350);
DISPLAY 0.723404 (3275 4350);
PAINT GREEN (3275 4350);
DISPLAY INVISIBLE (3275 4350);
FORCEPROP 1 LAST CDS_LMAN_SYM_OUTLINE -300,700,250,-650
J 0
(3275 4350);
DISPLAY 0.468085 (3275 4350);
PAINT GREEN (3275 4350);
DISPLAY INVISIBLE (3275 4350);
FORCEPROP 1 LAST PATH I23
J 0
(3275 4350);
DISPLAY 0.723404 (3275 4350);
PAINT GREEN (3275 4350);
DISPLAY INVISIBLE (3275 4350);
FORCEPROP 1 LAST PART_NUMBER AL099390004
J 0
(2975 5150);
DISPLAY 0.489362 (2975 5150);
PAINT SKYBLUE (2975 5150);
DISPLAY INVISIBLE (2975 5150);
FORCEADD Q_CAP..1
(4050 2450);
FORCEPROP 1 LAST LOCATION PC115_4
J 0
(4125 2575);
DISPLAY 0.489362 (4125 2575);
PAINT SKYBLUE (4125 2575);
FORCEPROP 0 LAST $SEC 1
J 0
(4100 2600);
DISPLAY 0.680851 (4100 2600);
PAINT MONO (4100 2600);
DISPLAY INVISIBLE (4100 2600);
FORCEPROP 0 LAST CDS_SEC 1
J 0
(4100 2600);
DISPLAY 1.021277 (4100 2600);
DISPLAY INVISIBLE (4100 2600);
FORCEPROP 1 LASTPIN (4050 2550) $PN 1
J 0
(4060 2530);
DISPLAY 0.489362 (4060 2530);
PAINT MONO (4060 2530);
FORCEPROP 1 LASTPIN (4050 2350) $PN 2
J 0
(4060 2330);
DISPLAY 0.489362 (4060 2330);
PAINT MONO (4060 2330);
FORCEPROP 1 LAST PACK_TYPE 0402
J 0
(4125 2275);
DISPLAY 0.489362 (4125 2275);
PAINT SKYBLUE (4125 2275);
FORCEPROP 1 LAST VALUE 0.1UF
J 0
(4125 2525);
DISPLAY 0.489362 (4125 2525);
PAINT SKYBLUE (4125 2525);
FORCEPROP 1 LAST TOLERANCE 10%
J 0
(4125 2425);
DISPLAY 0.489362 (4125 2425);
PAINT SKYBLUE (4125 2425);
FORCEPROP 1 LAST MATERIAL X7R
J 0
(4125 2375);
DISPLAY 0.489362 (4125 2375);
PAINT SKYBLUE (4125 2375);
FORCEPROP 1 LAST VOLTAGE 25V
J 0
(4125 2475);
DISPLAY 0.489362 (4125 2475);
PAINT SKYBLUE (4125 2475);
FORCEPROP 2 LAST CDS_LIB pure_quanta
J 0
(4050 2450);
DISPLAY INVISIBLE (4050 2450);
FORCEPROP 1 LAST PATH I24
J 0
(4100 2600);
DISPLAY 0.978723 (4100 2600);
PAINT WHITE (4100 2600);
DISPLAY INVISIBLE (4100 2600);
FORCEPROP 1 LAST PART_NUMBER CH4104K1B00
J 0
(4125 2325);
DISPLAY 0.489362 (4125 2325);
PAINT SKYBLUE (4125 2325);
DISPLAY INVISIBLE (4125 2325);
FORCEADD UNIVERSAL_GND..1
(3925 3625);
FORCEPROP 3 LASTPIN (3925 3675) SIG_NAME GND\g
J 0
(3935 3685);
DISPLAY 0.659574 (3935 3685);
PAINT MONO (3935 3685);
DISPLAY INVISIBLE (3935 3685);
FORCEPROP 2 LAST CDS_LIB pure_quanta_power
J 0
(3925 3625);
PAINT MONO (3925 3625);
DISPLAY INVISIBLE (3925 3625);
FORCEPROP 1 LAST HDL_POWER GND
J 1
(3950 3550);
DISPLAY 0.872340 (3950 3550);
PAINT GREEN (3950 3550);
DISPLAY INVISIBLE (3950 3550);
FORCEPROP 1 LAST PATH I25
J 0
(4000 3625);
DISPLAY 0.872340 (4000 3625);
PAINT AQUA (4000 3625);
DISPLAY INVISIBLE (4000 3625);
FORCEADD OFFPAGE..1
(1825 4250);
FORCEPROP 2 LAST $XR5 206 
J 0
(973 4250);
DISPLAY 0.638298 (973 4250);
PAINT MONO (973 4250);
FORCEPROP 2 LAST $XR4 205 
J 0
(1093 4250);
DISPLAY 0.638298 (1093 4250);
PAINT MONO (1093 4250);
FORCEPROP 2 LAST $XR3 203 
J 0
(1213 4250);
DISPLAY 0.638298 (1213 4250);
PAINT MONO (1213 4250);
FORCEPROP 2 LAST $XR2 202 
J 0
(1333 4250);
DISPLAY 0.638298 (1333 4250);
PAINT MONO (1333 4250);
FORCEPROP 2 LAST $XR1 201 
J 0
(1453 4250);
DISPLAY 0.638298 (1453 4250);
PAINT MONO (1453 4250);
FORCEPROP 2 LAST $XR0 200 
J 0
(1573 4250);
DISPLAY 0.638298 (1573 4250);
PAINT MONO (1573 4250);
FORCEPROP 2 LAST CDS_LIB standard
J 0
(1825 4250);
DISPLAY INVISIBLE (1825 4250);
FORCEPROP 1 LAST OFFPAGE TRUE
J 0
(2150 4125);
DISPLAY 0.872340 (2150 4125);
PAINT GREEN (2150 4125);
DISPLAY INVISIBLE (2150 4125);
FORCEPROP 1 LAST COMMENT_BODY TRUE
J 0
(1950 4150);
DISPLAY 0.872340 (1950 4150);
PAINT GREEN (1950 4150);
DISPLAY INVISIBLE (1950 4150);
FORCEPROP 2 LAST PATH I26
J 0
(1575 4300);
DISPLAY 0.680851 (1575 4300);
DISPLAY INVISIBLE (1575 4300);
FORCEADD OFFPAGE..5
(1825 4350);
FORCEPROP 2 LAST $XR0 200 
J 0
(1540 4350);
DISPLAY 0.638298 (1540 4350);
PAINT MONO (1540 4350);
FORCEPROP 2 LAST CDS_LIB standard
J 0
(1825 4350);
DISPLAY INVISIBLE (1825 4350);
FORCEPROP 1 LAST OFFPAGE TRUE
J 0
(2150 4225);
DISPLAY 0.872340 (2150 4225);
PAINT GREEN (2150 4225);
DISPLAY INVISIBLE (2150 4225);
FORCEPROP 1 LAST COMMENT_BODY TRUE
J 0
(1925 4275);
DISPLAY 0.872340 (1925 4275);
PAINT GREEN (1925 4275);
DISPLAY INVISIBLE (1925 4275);
FORCEPROP 2 LAST PATH I27
J 0
(1575 4400);
DISPLAY 0.680851 (1575 4400);
DISPLAY INVISIBLE (1575 4400);
FORCEADD Q_CAP..1
(1650 4800);
FORCEPROP 1 LAST LOCATION PC110
J 0
(1700 4900);
DISPLAY 0.489362 (1700 4900);
PAINT SKYBLUE (1700 4900);
FORCEPROP 0 LAST $SEC 1
J 0
(1700 4950);
DISPLAY 0.680851 (1700 4950);
PAINT MONO (1700 4950);
DISPLAY INVISIBLE (1700 4950);
FORCEPROP 0 LAST CDS_SEC 1
J 0
(1700 4950);
DISPLAY 1.021277 (1700 4950);
DISPLAY INVISIBLE (1700 4950);
FORCEPROP 1 LASTPIN (1650 4900) $PN 1
J 0
(1660 4880);
DISPLAY 0.489362 (1660 4880);
PAINT MONO (1660 4880);
FORCEPROP 1 LASTPIN (1650 4700) $PN 2
J 0
(1660 4680);
DISPLAY 0.489362 (1660 4680);
PAINT MONO (1660 4680);
FORCEPROP 1 LAST VOLTAGE 10V
J 0
(1700 4800);
DISPLAY 0.489362 (1700 4800);
PAINT SKYBLUE (1700 4800);
FORCEPROP 1 LAST VALUE 2.2UF
J 0
(1700 4850);
DISPLAY 0.489362 (1700 4850);
PAINT SKYBLUE (1700 4850);
FORCEPROP 1 LAST TOLERANCE 10%
J 0
(1700 4750);
DISPLAY 0.489362 (1700 4750);
PAINT SKYBLUE (1700 4750);
FORCEPROP 1 LAST MATERIAL X6S
J 0
(1700 4700);
DISPLAY 0.489362 (1700 4700);
PAINT SKYBLUE (1700 4700);
FORCEPROP 1 LAST PACK_TYPE C0402
J 0
(1700 4600);
DISPLAY 0.489362 (1700 4600);
PAINT SKYBLUE (1700 4600);
FORCEPROP 2 LAST CDS_LIB pure_quanta
J 0
(1650 4800);
DISPLAY INVISIBLE (1650 4800);
FORCEPROP 1 LAST PATH I28
J 0
(1700 4950);
DISPLAY 0.978723 (1700 4950);
PAINT WHITE (1700 4950);
DISPLAY INVISIBLE (1700 4950);
FORCEPROP 1 LAST PART_NUMBER CH5222KEB01
J 0
(1700 4650);
DISPLAY 0.489362 (1700 4650);
PAINT SKYBLUE (1700 4650);
DISPLAY INVISIBLE (1700 4650);
FORCEADD UNIVERSAL_GND..1
(1650 4600);
FORCEPROP 3 LASTPIN (1650 4650) SIG_NAME GND\g
J 0
(1660 4660);
DISPLAY 0.659574 (1660 4660);
PAINT MONO (1660 4660);
DISPLAY INVISIBLE (1660 4660);
FORCEPROP 2 LAST CDS_LIB pure_quanta_power
J 0
(1650 4600);
DISPLAY INVISIBLE (1650 4600);
FORCEPROP 1 LAST HDL_POWER GND
J 1
(1675 4525);
DISPLAY 0.872340 (1675 4525);
PAINT GREEN (1675 4525);
DISPLAY INVISIBLE (1675 4525);
FORCEPROP 1 LAST PATH I29
J 0
(1725 4600);
DISPLAY 0.872340 (1725 4600);
PAINT AQUA (1725 4600);
DISPLAY INVISIBLE (1725 4600);
FORCEADD UNIVERSAL_GND..1
(1325 800);
FORCEPROP 3 LASTPIN (1325 850) SIG_NAME GND\g
J 0
(1335 860);
DISPLAY 0.659574 (1335 860);
PAINT MONO (1335 860);
DISPLAY INVISIBLE (1335 860);
FORCEPROP 2 LAST CDS_LIB pure_quanta_power
J 0
(1325 800);
PAINT MONO (1325 800);
DISPLAY INVISIBLE (1325 800);
FORCEPROP 1 LAST HDL_POWER GND
J 1
(1350 725);
DISPLAY 0.872340 (1350 725);
PAINT GREEN (1350 725);
DISPLAY INVISIBLE (1350 725);
FORCEPROP 1 LAST PATH I3
J 0
(1400 800);
DISPLAY 0.872340 (1400 800);
PAINT AQUA (1400 800);
DISPLAY INVISIBLE (1400 800);
FORCEADD Q_RES..2
(1650 5350);
FORCEPROP 1 LAST LOCATION PR88
J 0
(1695 5475);
DISPLAY 0.489362 (1695 5475);
PAINT SKYBLUE (1695 5475);
FORCEPROP 0 LAST $SEC 1
J 0
(1700 5525);
DISPLAY 0.680851 (1700 5525);
PAINT MONO (1700 5525);
DISPLAY INVISIBLE (1700 5525);
FORCEPROP 0 LAST CDS_SEC 1
J 0
(1700 5525);
DISPLAY 1.021277 (1700 5525);
DISPLAY INVISIBLE (1700 5525);
FORCEPROP 1 LASTPIN (1650 5450) $PN 1
J 0
(1655 5412);
DISPLAY 0.489362 (1655 5412);
PAINT MONO (1655 5412);
FORCEPROP 1 LASTPIN (1650 5250) $PN 2
J 0
(1655 5260);
DISPLAY 0.489362 (1655 5260);
PAINT MONO (1655 5260);
FORCEPROP 1 LAST WATTAGE 1/16W
J 0
(1700 5325);
DISPLAY 0.489362 (1700 5325);
PAINT SKYBLUE (1700 5325);
FORCEPROP 1 LAST MATERIAL CHIP
J 0
(1700 5275);
DISPLAY 0.489362 (1700 5275);
PAINT SKYBLUE (1700 5275);
FORCEPROP 1 LAST TOLERANCE 1%
J 0
(1700 5375);
DISPLAY 0.489362 (1700 5375);
PAINT SKYBLUE (1700 5375);
FORCEPROP 1 LAST VALUE 2.2
J 0
(1700 5425);
DISPLAY 0.489362 (1700 5425);
PAINT SKYBLUE (1700 5425);
FORCEPROP 1 LAST PACK_TYPE 0402LF
J 0
(1700 5175);
DISPLAY 0.489362 (1700 5175);
PAINT SKYBLUE (1700 5175);
FORCEPROP 2 LAST CDS_LIB pure_quanta
J 0
(1650 5350);
DISPLAY INVISIBLE (1650 5350);
FORCEPROP 1 LAST PATH I30
J 0
(1700 5525);
DISPLAY 0.978723 (1700 5525);
PAINT WHITE (1700 5525);
DISPLAY INVISIBLE (1700 5525);
FORCEPROP 1 LAST PART_NUMBER CS-2202FB01
J 0
(1700 5225);
DISPLAY 0.489362 (1700 5225);
PAINT SKYBLUE (1700 5225);
DISPLAY INVISIBLE (1700 5225);
FORCEADD UNIVERSAL_GND..1
(2000 5100);
FORCEPROP 3 LASTPIN (2000 5150) SIG_NAME GND\g
J 0
(2010 5160);
DISPLAY 0.659574 (2010 5160);
PAINT MONO (2010 5160);
DISPLAY INVISIBLE (2010 5160);
FORCEPROP 2 LAST CDS_LIB pure_quanta_power
J 0
(2000 5100);
DISPLAY INVISIBLE (2000 5100);
FORCEPROP 1 LAST HDL_POWER GND
J 1
(2025 5025);
DISPLAY 0.872340 (2025 5025);
PAINT GREEN (2025 5025);
DISPLAY INVISIBLE (2025 5025);
FORCEPROP 1 LAST PATH I31
J 0
(2075 5100);
DISPLAY 0.872340 (2075 5100);
PAINT AQUA (2075 5100);
DISPLAY INVISIBLE (2075 5100);
FORCEADD Q_CAP..1
(2000 5375);
FORCEPROP 1 LAST LOCATION PC112_C1P0_3
J 0
(2050 5475);
DISPLAY 0.489362 (2050 5475);
PAINT SKYBLUE (2050 5475);
FORCEPROP 0 LAST $SEC 1
J 0
(2050 5525);
DISPLAY 0.680851 (2050 5525);
PAINT MONO (2050 5525);
DISPLAY INVISIBLE (2050 5525);
FORCEPROP 0 LAST CDS_SEC 1
J 0
(2050 5525);
DISPLAY 1.021277 (2050 5525);
DISPLAY INVISIBLE (2050 5525);
FORCEPROP 1 LASTPIN (2000 5475) $PN 1
J 0
(2010 5455);
DISPLAY 0.489362 (2010 5455);
PAINT MONO (2010 5455);
FORCEPROP 1 LASTPIN (2000 5275) $PN 2
J 0
(2010 5255);
DISPLAY 0.489362 (2010 5255);
PAINT MONO (2010 5255);
FORCEPROP 1 LAST PACK_TYPE C0402
J 0
(2050 5175);
DISPLAY 0.489362 (2050 5175);
PAINT SKYBLUE (2050 5175);
FORCEPROP 1 LAST VOLTAGE 10V
J 0
(2050 5375);
DISPLAY 0.489362 (2050 5375);
PAINT SKYBLUE (2050 5375);
FORCEPROP 1 LAST VALUE 2.2UF
J 0
(2050 5425);
DISPLAY 0.489362 (2050 5425);
PAINT SKYBLUE (2050 5425);
FORCEPROP 1 LAST TOLERANCE 10%
J 0
(2050 5325);
DISPLAY 0.489362 (2050 5325);
PAINT SKYBLUE (2050 5325);
FORCEPROP 1 LAST MATERIAL X6S
J 0
(2050 5275);
DISPLAY 0.489362 (2050 5275);
PAINT SKYBLUE (2050 5275);
FORCEPROP 2 LAST CDS_LIB pure_quanta
J 0
(2000 5375);
DISPLAY INVISIBLE (2000 5375);
FORCEPROP 1 LAST PATH I32
J 0
(2050 5525);
DISPLAY 0.978723 (2050 5525);
PAINT WHITE (2050 5525);
DISPLAY INVISIBLE (2050 5525);
FORCEPROP 1 LAST PART_NUMBER CH5222KEB01
J 0
(2050 5225);
DISPLAY 0.489362 (2050 5225);
PAINT SKYBLUE (2050 5225);
DISPLAY INVISIBLE (2050 5225);
FORCEADD VCC_CORE..1
(1650 5775);
FORCEPROP 3 LASTPIN (1650 5725) SIG_NAME PVDDCR_CPU1_P0_PVCC\g
J 0
(1660 5735);
DISPLAY 0.659574 (1660 5735);
PAINT MONO (1660 5735);
DISPLAY INVISIBLE (1660 5735);
FORCEPROP 1 LAST HDL_POWER PVDDCR_CPU1_P0_PVCC
J 1
(1650 5825);
DISPLAY 0.489362 (1650 5825);
PAINT GREEN (1650 5825);
FORCEPROP 2 LAST CDS_LIB pure_quanta_power
J 0
(1650 5775);
DISPLAY INVISIBLE (1650 5775);
FORCEPROP 1 LAST PATH I33
J 0
(1700 5800);
DISPLAY 0.872340 (1700 5800);
PAINT AQUA (1700 5800);
DISPLAY INVISIBLE (1700 5800);
FORCEADD Q_CAP..1
(4100 5300);
FORCEPROP 1 LAST LOCATION PC116_3
J 0
(4150 5400);
DISPLAY 0.489362 (4150 5400);
PAINT SKYBLUE (4150 5400);
FORCEPROP 0 LAST $SEC 1
J 0
(4150 5450);
DISPLAY 0.680851 (4150 5450);
PAINT MONO (4150 5450);
DISPLAY INVISIBLE (4150 5450);
FORCEPROP 0 LAST CDS_SEC 1
J 0
(4150 5450);
DISPLAY 1.021277 (4150 5450);
DISPLAY INVISIBLE (4150 5450);
FORCEPROP 1 LASTPIN (4100 5400) $PN 1
J 0
(4110 5380);
DISPLAY 0.489362 (4110 5380);
PAINT MONO (4110 5380);
FORCEPROP 1 LASTPIN (4100 5200) $PN 2
J 0
(4110 5180);
DISPLAY 0.489362 (4110 5180);
PAINT MONO (4110 5180);
FORCEPROP 1 LAST VOLTAGE 25V
J 0
(4150 5300);
DISPLAY 0.489362 (4150 5300);
PAINT SKYBLUE (4150 5300);
FORCEPROP 1 LAST VALUE 0.1UF
J 0
(4150 5350);
DISPLAY 0.489362 (4150 5350);
PAINT SKYBLUE (4150 5350);
FORCEPROP 1 LAST TOLERANCE 10%
J 0
(4150 5250);
DISPLAY 0.489362 (4150 5250);
PAINT SKYBLUE (4150 5250);
FORCEPROP 1 LAST MATERIAL X7R
J 0
(4150 5200);
DISPLAY 0.489362 (4150 5200);
PAINT SKYBLUE (4150 5200);
FORCEPROP 1 LAST PACK_TYPE 0402
J 0
(4150 5100);
DISPLAY 0.489362 (4150 5100);
PAINT SKYBLUE (4150 5100);
FORCEPROP 2 LAST CDS_LIB pure_quanta
J 0
(4100 5300);
DISPLAY INVISIBLE (4100 5300);
FORCEPROP 1 LAST PATH I34
J 0
(4150 5450);
DISPLAY 0.978723 (4150 5450);
PAINT WHITE (4150 5450);
DISPLAY INVISIBLE (4150 5450);
FORCEPROP 1 LAST PART_NUMBER CH4104K1B00
J 0
(4150 5150);
DISPLAY 0.489362 (4150 5150);
PAINT SKYBLUE (4150 5150);
DISPLAY INVISIBLE (4150 5150);
FORCEADD UNIVERSAL_GND..1
(4650 600);
FORCEPROP 3 LASTPIN (4650 650) SIG_NAME GND\g
J 0
(4660 660);
DISPLAY 0.659574 (4660 660);
PAINT MONO (4660 660);
DISPLAY INVISIBLE (4660 660);
FORCEPROP 2 LAST CDS_LIB pure_quanta_power
J 0
(4650 600);
DISPLAY INVISIBLE (4650 600);
FORCEPROP 1 LAST HDL_POWER GND
J 1
(4675 525);
DISPLAY 0.872340 (4675 525);
PAINT GREEN (4675 525);
DISPLAY INVISIBLE (4675 525);
FORCEPROP 1 LAST PATH I35
J 0
(4725 600);
DISPLAY 0.872340 (4725 600);
PAINT AQUA (4725 600);
DISPLAY INVISIBLE (4725 600);
FORCEADD Q_RES..2
(4650 825);
FORCEPROP 1 LAST LOCATION PR509
J 0
(4695 950);
DISPLAY 0.489362 (4695 950);
PAINT SKYBLUE (4695 950);
FORCEPROP 0 LAST $SEC 1
J 0
(4700 1000);
DISPLAY 0.680851 (4700 1000);
PAINT MONO (4700 1000);
DISPLAY INVISIBLE (4700 1000);
FORCEPROP 0 LAST CDS_SEC 1
J 0
(4700 1000);
DISPLAY 1.021277 (4700 1000);
DISPLAY INVISIBLE (4700 1000);
FORCEPROP 1 LASTPIN (4650 925) $PN 1
J 0
(4655 887);
DISPLAY 0.489362 (4655 887);
PAINT MONO (4655 887);
FORCEPROP 1 LASTPIN (4650 725) $PN 2
J 0
(4655 735);
DISPLAY 0.489362 (4655 735);
PAINT MONO (4655 735);
FORCEPROP 1 LAST PACK_TYPE 0402LF
J 0
(4690 650);
DISPLAY 0.489362 (4690 650);
PAINT SKYBLUE (4690 650);
FORCEPROP 1 LAST VALUE 1.5
J 0
(4695 900);
DISPLAY 0.489362 (4695 900);
PAINT SKYBLUE (4695 900);
FORCEPROP 1 LAST TOLERANCE 1%
J 0
(4695 850);
DISPLAY 0.489362 (4695 850);
PAINT SKYBLUE (4695 850);
FORCEPROP 1 LAST MATERIAL EMPTY
J 0
(4690 750);
DISPLAY 0.489362 (4690 750);
PAINT RED (4690 750);
FORCEPROP 1 LAST WATTAGE 1/8W
J 0
(4690 800);
DISPLAY 0.489362 (4690 800);
PAINT SKYBLUE (4690 800);
FORCEPROP 2 LAST CDS_LIB pure_quanta
J 0
(4650 825);
DISPLAY INVISIBLE (4650 825);
FORCEPROP 1 LAST PATH I36
J 0
(4700 1000);
DISPLAY 0.978723 (4700 1000);
PAINT WHITE (4700 1000);
DISPLAY INVISIBLE (4700 1000);
FORCEPROP 1 LAST PART_NUMBER CS-1504FB00
J 0
(4690 700);
DISPLAY 0.489362 (4690 700);
PAINT SKYBLUE (4690 700);
DISPLAY INVISIBLE (4690 700);
FORCEADD Q_RES..1
(4500 1875);
FORCEPROP 1 LAST LOCATION PR89
J 0
(4275 1950);
DISPLAY 0.489362 (4275 1950);
PAINT SKYBLUE (4275 1950);
FORCEPROP 0 LAST $SEC 1
J 0
(4775 1975);
DISPLAY 0.680851 (4775 1975);
PAINT MONO (4775 1975);
DISPLAY INVISIBLE (4775 1975);
FORCEPROP 0 LAST CDS_SEC 1
J 0
(4775 1975);
DISPLAY 1.021277 (4775 1975);
DISPLAY INVISIBLE (4775 1975);
FORCEPROP 1 LASTPIN (4400 1875) $PN 1
J 0
(4412 1887);
DISPLAY 0.787234 (4412 1887);
PAINT MONO (4412 1887);
DISPLAY INVISIBLE (4412 1887);
FORCEPROP 1 LASTPIN (4600 1875) $PN 2
J 0
(4562 1887);
DISPLAY 0.787234 (4562 1887);
PAINT MONO (4562 1887);
DISPLAY INVISIBLE (4562 1887);
FORCEPROP 1 LAST WATTAGE 1/16W
J 2
(4775 1950);
DISPLAY 0.489362 (4775 1950);
PAINT SKYBLUE (4775 1950);
FORCEPROP 1 LAST MATERIAL CHIP
J 0
(4350 1800);
DISPLAY 0.489362 (4350 1800);
PAINT SKYBLUE (4350 1800);
FORCEPROP 1 LAST PACK_TYPE 0402LF
J 0
(4900 1800);
DISPLAY 0.489362 (4900 1800);
PAINT SKYBLUE (4900 1800);
FORCEPROP 1 LAST TOLERANCE 1%
J 0
(4500 1950);
DISPLAY 0.489362 (4500 1950);
PAINT SKYBLUE (4500 1950);
FORCEPROP 1 LAST VALUE 5.6
J 2
(4450 1950);
DISPLAY 0.489362 (4450 1950);
PAINT SKYBLUE (4450 1950);
FORCEPROP 2 LAST CDS_LIB pure_quanta
J 0
(4500 1875);
DISPLAY INVISIBLE (4500 1875);
FORCEPROP 1 LAST PATH I37
J 0
(4450 2025);
DISPLAY 0.978723 (4450 2025);
PAINT WHITE (4450 2025);
DISPLAY INVISIBLE (4450 2025);
FORCEPROP 1 LAST PART_NUMBER CS-5602FB01
J 0
(4525 1800);
DISPLAY 0.489362 (4525 1800);
PAINT SKYBLUE (4525 1800);
DISPLAY INVISIBLE (4525 1800);
FORCEADD Q_CAP..1
(4650 1350);
FORCEPROP 1 LAST LOCATION PC191
J 0
(4700 1450);
DISPLAY 0.489362 (4700 1450);
PAINT SKYBLUE (4700 1450);
FORCEPROP 0 LAST $SEC 1
J 0
(4700 1500);
DISPLAY 0.680851 (4700 1500);
PAINT MONO (4700 1500);
DISPLAY INVISIBLE (4700 1500);
FORCEPROP 0 LAST CDS_SEC 1
J 0
(4700 1500);
DISPLAY 1.021277 (4700 1500);
DISPLAY INVISIBLE (4700 1500);
FORCEPROP 1 LASTPIN (4650 1450) $PN 1
J 0
(4660 1430);
DISPLAY 0.489362 (4660 1430);
PAINT MONO (4660 1430);
FORCEPROP 1 LASTPIN (4650 1250) $PN 2
J 0
(4660 1230);
DISPLAY 0.489362 (4660 1230);
PAINT MONO (4660 1230);
FORCEPROP 1 LAST PACK_TYPE C0402
J 0
(4700 1150);
DISPLAY 0.489362 (4700 1150);
PAINT SKYBLUE (4700 1150);
FORCEPROP 1 LAST VOLTAGE 50V
J 0
(4700 1350);
DISPLAY 0.489362 (4700 1350);
PAINT SKYBLUE (4700 1350);
FORCEPROP 1 LAST VALUE 560PF
J 0
(4700 1400);
DISPLAY 0.489362 (4700 1400);
PAINT SKYBLUE (4700 1400);
FORCEPROP 1 LAST TOLERANCE 10%
J 0
(4700 1300);
DISPLAY 0.489362 (4700 1300);
PAINT SKYBLUE (4700 1300);
FORCEPROP 1 LAST MATERIAL EMPTY
J 0
(4700 1250);
DISPLAY 0.489362 (4700 1250);
PAINT RED (4700 1250);
FORCEPROP 2 LAST CDS_LIB pure_quanta
J 0
(4650 1350);
DISPLAY INVISIBLE (4650 1350);
FORCEPROP 1 LAST PATH I38
J 0
(4700 1500);
DISPLAY 0.978723 (4700 1500);
PAINT WHITE (4700 1500);
DISPLAY INVISIBLE (4700 1500);
FORCEPROP 1 LAST PART_NUMBER CH1566K1B09
J 0
(4700 1200);
DISPLAY 0.489362 (4700 1200);
PAINT SKYBLUE (4700 1200);
DISPLAY INVISIBLE (4700 1200);
FORCEADD OFFPAGE..6
(5225 1275);
FORCEPROP 2 LAST $XR0 202 
J 0
(4915 1275);
DISPLAY 0.638298 (4915 1275);
PAINT MONO (4915 1275);
FORCEPROP 2 LAST CDS_LIB standard
J 0
(5225 1275);
DISPLAY INVISIBLE (5225 1275);
FORCEPROP 1 LAST OFFPAGE TRUE
J 0
(5550 1150);
DISPLAY 0.872340 (5550 1150);
PAINT GREEN (5550 1150);
DISPLAY INVISIBLE (5550 1150);
FORCEPROP 1 LAST COMMENT_BODY TRUE
J 0
(5325 1200);
DISPLAY 0.872340 (5325 1200);
PAINT GREEN (5325 1200);
DISPLAY INVISIBLE (5325 1200);
FORCEPROP 2 LAST PATH I39
J 0
(4950 1325);
DISPLAY 0.680851 (4950 1325);
DISPLAY INVISIBLE (4950 1325);
FORCEADD Q_RES..2
R 2
(1325 1025);
FORCEPROP 1 LAST LOCATION PR85
J 2
(1280 1150);
DISPLAY 0.489362 (1280 1150);
PAINT SKYBLUE (1280 1150);
FORCEPROP 0 LAST $SEC 1
J 0
(1300 1200);
DISPLAY 0.680851 (1300 1200);
PAINT MONO (1300 1200);
DISPLAY INVISIBLE (1300 1200);
FORCEPROP 0 LAST CDS_SEC 1
J 0
(1300 1200);
DISPLAY 1.021277 (1300 1200);
DISPLAY INVISIBLE (1300 1200);
FORCEPROP 1 LASTPIN (1325 1125) $PN 1
J 2
(1320 1087);
DISPLAY 0.489362 (1320 1087);
PAINT MONO (1320 1087);
FORCEPROP 1 LASTPIN (1325 925) $PN 2
J 2
(1320 935);
DISPLAY 0.489362 (1320 935);
PAINT MONO (1320 935);
FORCEPROP 1 LAST WATTAGE 1/16W
J 2
(1285 1000);
DISPLAY 0.489362 (1285 1000);
PAINT SKYBLUE (1285 1000);
FORCEPROP 1 LAST MATERIAL EMPTY
J 2
(1285 950);
DISPLAY 0.489362 (1285 950);
PAINT RED (1285 950);
FORCEPROP 1 LAST TOLERANCE 1%
J 2
(1280 1050);
DISPLAY 0.489362 (1280 1050);
PAINT SKYBLUE (1280 1050);
FORCEPROP 1 LAST VALUE 8.87K
J 2
(1280 1100);
DISPLAY 0.489362 (1280 1100);
PAINT SKYBLUE (1280 1100);
FORCEPROP 1 LAST PACK_TYPE 0402LF
J 2
(1285 850);
DISPLAY 0.489362 (1285 850);
PAINT SKYBLUE (1285 850);
FORCEPROP 2 LAST CDS_LIB pure_quanta
J 2
(1325 1025);
DISPLAY INVISIBLE (1325 1025);
FORCEPROP 1 LAST PATH I4
J 2
(1275 1200);
DISPLAY 0.978723 (1275 1200);
PAINT WHITE (1275 1200);
DISPLAY INVISIBLE (1275 1200);
FORCEPROP 1 LAST PART_NUMBER CS28872FB01
J 2
(1285 900);
DISPLAY 0.489362 (1285 900);
PAINT SKYBLUE (1285 900);
DISPLAY INVISIBLE (1285 900);
FORCEADD Q_RES..1
(5850 525);
FORCEPROP 1 LAST LOCATION PR91
J 0
(5825 550);
DISPLAY 0.489362 (5825 550);
PAINT SKYBLUE (5825 550);
FORCEPROP 0 LAST $SEC 1
J 0
(6100 675);
DISPLAY 0.680851 (6100 675);
PAINT MONO (6100 675);
DISPLAY INVISIBLE (6100 675);
FORCEPROP 0 LAST CDS_SEC 1
J 0
(6100 675);
DISPLAY 1.021277 (6100 675);
DISPLAY INVISIBLE (6100 675);
FORCEPROP 1 LASTPIN (5750 525) $PN 1
J 0
(5762 537);
DISPLAY 0.489362 (5762 537);
PAINT MONO (5762 537);
FORCEPROP 1 LASTPIN (5950 525) $PN 2
J 0
(5912 537);
DISPLAY 0.489362 (5912 537);
PAINT MONO (5912 537);
FORCEPROP 1 LAST WATTAGE 1/16W
J 2
(6100 600);
DISPLAY 0.489362 (6100 600);
PAINT SKYBLUE (6100 600);
FORCEPROP 1 LAST MATERIAL CHIP
J 0
(6000 550);
DISPLAY 0.489362 (6000 550);
PAINT SKYBLUE (6000 550);
FORCEPROP 1 LAST TOLERANCE 5%
J 0
(5675 550);
DISPLAY 0.489362 (5675 550);
PAINT SKYBLUE (5675 550);
FORCEPROP 1 LAST VALUE 0
J 2
(5650 550);
DISPLAY 0.489362 (5650 550);
PAINT SKYBLUE (5650 550);
FORCEPROP 1 LAST PACK_TYPE 0402LF
J 0
(5975 475);
DISPLAY 0.489362 (5975 475);
PAINT SKYBLUE (5975 475);
FORCEPROP 2 LAST CDS_LIB pure_quanta
J 0
(5850 525);
DISPLAY INVISIBLE (5850 525);
FORCEPROP 1 LAST PATH I40
J 0
(5800 675);
DISPLAY 0.978723 (5800 675);
PAINT WHITE (5800 675);
DISPLAY INVISIBLE (5800 675);
FORCEPROP 1 LAST PART_NUMBER CS00002JB13
J 0
(5550 475);
DISPLAY 0.489362 (5550 475);
PAINT SKYBLUE (5550 475);
DISPLAY INVISIBLE (5550 475);
FORCEADD Q_CAP..1
(5225 1750);
FORCEPROP 1 LAST LOCATION PC121
J 0
(5275 1850);
DISPLAY 0.489362 (5275 1850);
PAINT SKYBLUE (5275 1850);
FORCEPROP 0 LAST $SEC 1
J 0
(5275 1900);
DISPLAY 0.680851 (5275 1900);
PAINT MONO (5275 1900);
DISPLAY INVISIBLE (5275 1900);
FORCEPROP 0 LAST CDS_SEC 1
J 2
(5275 1875);
DISPLAY 1.021277 (5275 1875);
DISPLAY INVISIBLE (5275 1875);
FORCEPROP 1 LASTPIN (5225 1850) $PN 1
J 0
(5235 1830);
DISPLAY 0.489362 (5235 1830);
PAINT MONO (5235 1830);
FORCEPROP 1 LASTPIN (5225 1650) $PN 2
J 0
(5235 1630);
DISPLAY 0.489362 (5235 1630);
PAINT MONO (5235 1630);
FORCEPROP 1 LAST VALUE 0.22UF
J 0
(5275 1800);
DISPLAY 0.489362 (5275 1800);
PAINT SKYBLUE (5275 1800);
FORCEPROP 1 LAST VOLTAGE 16V
J 0
(5275 1750);
DISPLAY 0.489362 (5275 1750);
PAINT SKYBLUE (5275 1750);
FORCEPROP 1 LAST TOLERANCE 10%
J 0
(5275 1700);
DISPLAY 0.489362 (5275 1700);
PAINT SKYBLUE (5275 1700);
FORCEPROP 1 LAST PACK_TYPE 0402
J 0
(5275 1550);
DISPLAY 0.489362 (5275 1550);
PAINT SKYBLUE (5275 1550);
FORCEPROP 1 LAST MATERIAL X7R
J 0
(5275 1650);
DISPLAY 0.489362 (5275 1650);
PAINT SKYBLUE (5275 1650);
FORCEPROP 2 LAST CDS_LIB pure_quanta
J 2
(5225 1750);
DISPLAY INVISIBLE (5225 1750);
FORCEPROP 1 LAST PATH I41
J 0
(5275 1900);
DISPLAY 0.978723 (5275 1900);
PAINT WHITE (5275 1900);
DISPLAY INVISIBLE (5275 1900);
FORCEPROP 1 LAST PART_NUMBER CH4223K1B00
J 0
(5275 1600);
DISPLAY 0.489362 (5275 1600);
PAINT SKYBLUE (5275 1600);
DISPLAY INVISIBLE (5275 1600);
FORCEADD Q_INDUCTOR4P_14..1
(6150 1400);
FORCEPROP 1 LAST LOCATION PL13
J 0
(5925 1655);
DISPLAY 0.489362 (5925 1655);
PAINT SKYBLUE (5925 1655);
FORCEPROP 0 LAST $SEC 1
J 0
(5925 1700);
DISPLAY 0.680851 (5925 1700);
PAINT MONO (5925 1700);
DISPLAY INVISIBLE (5925 1700);
FORCEPROP 0 LAST CDS_SEC 1
J 0
(5925 1700);
DISPLAY 1.021277 (5925 1700);
DISPLAY INVISIBLE (5925 1700);
FORCEPROP 0 LASTPIN (5750 1525) $PN 1
J 2
(5740 1535);
DISPLAY 0.489362 (5740 1535);
PAINT MONO (5740 1535);
FORCEPROP 0 LASTPIN (5750 1275) $PN 2
J 2
(5740 1285);
DISPLAY 0.489362 (5740 1285);
PAINT MONO (5740 1285);
FORCEPROP 0 LASTPIN (6550 1275) $PN 3
J 0
(6560 1285);
DISPLAY 0.489362 (6560 1285);
PAINT MONO (6560 1285);
FORCEPROP 0 LASTPIN (6550 1525) $PN 4
J 0
(6560 1535);
DISPLAY 0.489362 (6560 1535);
PAINT MONO (6560 1535);
FORCEPROP 2 LAST VALUE 150NH
J 0
(6050 1575);
DISPLAY 0.489362 (6050 1575);
PAINT SKYBLUE (6050 1575);
FORCEPROP 1 LAST MATERIAL IND
J 0
(5950 1575);
DISPLAY 0.489362 (5950 1575);
PAINT SKYBLUE (5950 1575);
FORCEPROP 2 LAST PART_TYPE SMLF
J 0
(6075 1150);
DISPLAY 1.021277 (6075 1150);
FORCEPROP 2 LAST CDS_LIB pure_quanta
J 0
(6150 1400);
DISPLAY INVISIBLE (6150 1400);
FORCEPROP 1 LAST NEEDS_NO_SIZE TRUE
J 0
(6150 1400);
DISPLAY 0.468085 (6150 1400);
PAINT GREEN (6150 1400);
DISPLAY INVISIBLE (6150 1400);
FORCEPROP 1 LAST PATH I42
J 0
(6350 1555);
DISPLAY 0.723404 (6350 1555);
PAINT GREEN (6350 1555);
DISPLAY INVISIBLE (6350 1555);
FORCEPROP 1 LAST PART_NUMBER CV+15^0TZ04
J 0
(6200 1575);
DISPLAY 0.489362 (6200 1575);
PAINT SKYBLUE (6200 1575);
DISPLAY INVISIBLE (6200 1575);
FORCEADD Q_CAP..1
(4450 2425);
FORCEPROP 1 LAST LOCATION PC117_4
J 0
(4500 2575);
DISPLAY 0.489362 (4500 2575);
PAINT SKYBLUE (4500 2575);
FORCEPROP 0 LAST $SEC 1
J 0
(4500 2625);
DISPLAY 0.680851 (4500 2625);
PAINT MONO (4500 2625);
DISPLAY INVISIBLE (4500 2625);
FORCEPROP 0 LAST CDS_SEC 1
J 0
(4500 2625);
DISPLAY 1.021277 (4500 2625);
DISPLAY INVISIBLE (4500 2625);
FORCEPROP 1 LASTPIN (4450 2525) $PN 1
J 0
(4460 2505);
DISPLAY 0.489362 (4460 2505);
PAINT MONO (4460 2505);
FORCEPROP 1 LASTPIN (4450 2325) $PN 2
J 0
(4460 2305);
DISPLAY 0.489362 (4460 2305);
PAINT MONO (4460 2305);
FORCEPROP 1 LAST TOLERANCE 10%
J 0
(4500 2425);
DISPLAY 0.489362 (4500 2425);
PAINT SKYBLUE (4500 2425);
FORCEPROP 1 LAST VOLTAGE 25V
J 0
(4500 2475);
DISPLAY 0.489362 (4500 2475);
PAINT SKYBLUE (4500 2475);
FORCEPROP 1 LAST VALUE 1UF
J 0
(4500 2525);
DISPLAY 0.489362 (4500 2525);
PAINT SKYBLUE (4500 2525);
FORCEPROP 1 LAST MATERIAL X6S
J 0
(4500 2375);
DISPLAY 0.489362 (4500 2375);
PAINT SKYBLUE (4500 2375);
FORCEPROP 1 LAST PACK_TYPE C0402
J 0
(4500 2325);
DISPLAY 0.489362 (4500 2325);
PAINT SKYBLUE (4500 2325);
FORCEPROP 2 LAST CDS_LIB pure_quanta
J 0
(4450 2425);
DISPLAY INVISIBLE (4450 2425);
FORCEPROP 1 LAST PATH I43
J 0
(4500 2575);
DISPLAY 0.978723 (4500 2575);
PAINT WHITE (4500 2575);
DISPLAY INVISIBLE (4500 2575);
FORCEPROP 1 LAST PART_NUMBER CH5104KEB02
J 0
(4500 2275);
DISPLAY 0.489362 (4500 2275);
PAINT SKYBLUE (4500 2275);
DISPLAY INVISIBLE (4500 2275);
FORCEADD Q_CAP..1
(4850 2425);
FORCEPROP 1 LAST LOCATION PC119_4
J 0
(4900 2575);
DISPLAY 0.489362 (4900 2575);
PAINT SKYBLUE (4900 2575);
FORCEPROP 0 LAST $SEC 1
J 0
(4900 2625);
DISPLAY 0.680851 (4900 2625);
PAINT MONO (4900 2625);
DISPLAY INVISIBLE (4900 2625);
FORCEPROP 0 LAST CDS_SEC 1
J 0
(4900 2625);
DISPLAY 1.021277 (4900 2625);
DISPLAY INVISIBLE (4900 2625);
FORCEPROP 1 LASTPIN (4850 2525) $PN 1
J 0
(4860 2505);
DISPLAY 0.489362 (4860 2505);
PAINT MONO (4860 2505);
FORCEPROP 1 LASTPIN (4850 2325) $PN 2
J 0
(4860 2305);
DISPLAY 0.489362 (4860 2305);
PAINT MONO (4860 2305);
FORCEPROP 1 LAST MATERIAL X6S
J 0
(4900 2375);
DISPLAY 0.489362 (4900 2375);
PAINT SKYBLUE (4900 2375);
FORCEPROP 1 LAST PACK_TYPE C0805
J 0
(4900 2325);
DISPLAY 0.489362 (4900 2325);
PAINT SKYBLUE (4900 2325);
FORCEPROP 1 LAST VALUE 22UF
J 0
(4900 2525);
DISPLAY 0.489362 (4900 2525);
PAINT SKYBLUE (4900 2525);
FORCEPROP 1 LAST VOLTAGE 16V
J 0
(4900 2475);
DISPLAY 0.489362 (4900 2475);
PAINT SKYBLUE (4900 2475);
FORCEPROP 1 LAST TOLERANCE 20%
J 0
(4900 2425);
DISPLAY 0.489362 (4900 2425);
PAINT SKYBLUE (4900 2425);
FORCEPROP 2 LAST CDS_LIB pure_quanta
J 0
(4850 2425);
DISPLAY INVISIBLE (4850 2425);
FORCEPROP 1 LAST PATH I44
J 0
(4900 2575);
DISPLAY 0.978723 (4900 2575);
PAINT WHITE (4900 2575);
DISPLAY INVISIBLE (4900 2575);
FORCEPROP 1 LAST PART_NUMBER CH6223MEA01
J 0
(4900 2275);
DISPLAY 0.489362 (4900 2275);
PAINT SKYBLUE (4900 2275);
DISPLAY INVISIBLE (4900 2275);
FORCEADD UNIVERSAL_GND..1
(4700 3375);
FORCEPROP 3 LASTPIN (4700 3425) SIG_NAME GND\g
J 0
(4710 3435);
DISPLAY 0.659574 (4710 3435);
PAINT MONO (4710 3435);
DISPLAY INVISIBLE (4710 3435);
FORCEPROP 2 LAST CDS_LIB pure_quanta_power
J 0
(4700 3375);
DISPLAY INVISIBLE (4700 3375);
FORCEPROP 1 LAST HDL_POWER GND
J 1
(4725 3300);
DISPLAY 0.872340 (4725 3300);
PAINT GREEN (4725 3300);
DISPLAY INVISIBLE (4725 3300);
FORCEPROP 1 LAST PATH I45
J 0
(4775 3375);
DISPLAY 0.872340 (4775 3375);
PAINT AQUA (4775 3375);
DISPLAY INVISIBLE (4775 3375);
FORCEADD Q_RES..2
(4700 3600);
FORCEPROP 1 LAST LOCATION PR510
J 0
(4745 3725);
DISPLAY 0.489362 (4745 3725);
PAINT SKYBLUE (4745 3725);
FORCEPROP 0 LAST $SEC 1
J 0
(4750 3775);
DISPLAY 0.680851 (4750 3775);
PAINT MONO (4750 3775);
DISPLAY INVISIBLE (4750 3775);
FORCEPROP 0 LAST CDS_SEC 1
J 0
(4750 3775);
DISPLAY 1.021277 (4750 3775);
DISPLAY INVISIBLE (4750 3775);
FORCEPROP 1 LASTPIN (4700 3700) $PN 1
J 0
(4705 3662);
DISPLAY 0.489362 (4705 3662);
PAINT MONO (4705 3662);
FORCEPROP 1 LASTPIN (4700 3500) $PN 2
J 0
(4705 3510);
DISPLAY 0.489362 (4705 3510);
PAINT MONO (4705 3510);
FORCEPROP 1 LAST MATERIAL EMPTY
J 0
(4740 3525);
DISPLAY 0.489362 (4740 3525);
PAINT RED (4740 3525);
FORCEPROP 1 LAST WATTAGE 1/8W
J 0
(4740 3575);
DISPLAY 0.489362 (4740 3575);
PAINT SKYBLUE (4740 3575);
FORCEPROP 1 LAST TOLERANCE 1%
J 0
(4745 3625);
DISPLAY 0.489362 (4745 3625);
PAINT SKYBLUE (4745 3625);
FORCEPROP 1 LAST VALUE 1.5
J 0
(4745 3675);
DISPLAY 0.489362 (4745 3675);
PAINT SKYBLUE (4745 3675);
FORCEPROP 1 LAST PACK_TYPE 0402LF
J 0
(4740 3425);
DISPLAY 0.489362 (4740 3425);
PAINT SKYBLUE (4740 3425);
FORCEPROP 2 LAST CDS_LIB pure_quanta
J 0
(4700 3600);
DISPLAY INVISIBLE (4700 3600);
FORCEPROP 1 LAST PATH I46
J 0
(4750 3775);
DISPLAY 0.978723 (4750 3775);
PAINT WHITE (4750 3775);
DISPLAY INVISIBLE (4750 3775);
FORCEPROP 1 LAST PART_NUMBER CS-1504FB00
J 0
(4740 3475);
DISPLAY 0.489362 (4740 3475);
PAINT SKYBLUE (4740 3475);
DISPLAY INVISIBLE (4740 3475);
FORCEADD Q_CAP..1
(5250 2425);
FORCEPROP 1 LAST LOCATION PC123_4
J 0
(5300 2575);
DISPLAY 0.489362 (5300 2575);
PAINT SKYBLUE (5300 2575);
FORCEPROP 0 LAST $SEC 1
J 0
(5300 2625);
DISPLAY 0.680851 (5300 2625);
PAINT MONO (5300 2625);
DISPLAY INVISIBLE (5300 2625);
FORCEPROP 0 LAST CDS_SEC 1
J 0
(5300 2625);
DISPLAY 1.021277 (5300 2625);
DISPLAY INVISIBLE (5300 2625);
FORCEPROP 1 LASTPIN (5250 2525) $PN 1
J 0
(5260 2505);
DISPLAY 0.489362 (5260 2505);
PAINT MONO (5260 2505);
FORCEPROP 1 LASTPIN (5250 2325) $PN 2
J 0
(5260 2305);
DISPLAY 0.489362 (5260 2305);
PAINT MONO (5260 2305);
FORCEPROP 1 LAST PACK_TYPE C0805
J 0
(5300 2325);
DISPLAY 0.489362 (5300 2325);
PAINT SKYBLUE (5300 2325);
FORCEPROP 1 LAST MATERIAL X6S
J 0
(5300 2375);
DISPLAY 0.489362 (5300 2375);
PAINT SKYBLUE (5300 2375);
FORCEPROP 1 LAST VALUE 22UF
J 0
(5300 2525);
DISPLAY 0.489362 (5300 2525);
PAINT SKYBLUE (5300 2525);
FORCEPROP 1 LAST VOLTAGE 16V
J 0
(5300 2475);
DISPLAY 0.489362 (5300 2475);
PAINT SKYBLUE (5300 2475);
FORCEPROP 1 LAST TOLERANCE 20%
J 0
(5300 2425);
DISPLAY 0.489362 (5300 2425);
PAINT SKYBLUE (5300 2425);
FORCEPROP 2 LAST CDS_LIB pure_quanta
J 0
(5250 2425);
DISPLAY INVISIBLE (5250 2425);
FORCEPROP 1 LAST PATH I47
J 0
(5300 2575);
DISPLAY 0.978723 (5300 2575);
PAINT WHITE (5300 2575);
DISPLAY INVISIBLE (5300 2575);
FORCEPROP 1 LAST PART_NUMBER CH6223MEA01
J 0
(5300 2275);
DISPLAY 0.489362 (5300 2275);
PAINT SKYBLUE (5300 2275);
DISPLAY INVISIBLE (5300 2275);
FORCEADD UNIVERSAL_GND..1
(5625 2050);
FORCEPROP 3 LASTPIN (5625 2100) SIG_NAME GND\g
J 0
(5635 2110);
DISPLAY 0.659574 (5635 2110);
PAINT MONO (5635 2110);
DISPLAY INVISIBLE (5635 2110);
FORCEPROP 2 LAST CDS_LIB pure_quanta_power
J 0
(5625 2050);
PAINT MONO (5625 2050);
DISPLAY INVISIBLE (5625 2050);
FORCEPROP 1 LAST HDL_POWER GND
J 1
(5650 1975);
DISPLAY 0.872340 (5650 1975);
PAINT GREEN (5650 1975);
DISPLAY INVISIBLE (5650 1975);
FORCEPROP 1 LAST PATH I48
J 0
(5700 2050);
DISPLAY 0.872340 (5700 2050);
PAINT AQUA (5700 2050);
DISPLAY INVISIBLE (5700 2050);
FORCEADD Q_CAP..1
(5625 2425);
FORCEPROP 1 LAST LOCATION PC125_4
J 0
(5675 2575);
DISPLAY 0.489362 (5675 2575);
PAINT SKYBLUE (5675 2575);
FORCEPROP 0 LAST $SEC 1
J 0
(5675 2625);
DISPLAY 0.680851 (5675 2625);
PAINT MONO (5675 2625);
DISPLAY INVISIBLE (5675 2625);
FORCEPROP 0 LAST CDS_SEC 1
J 0
(5675 2625);
DISPLAY 1.021277 (5675 2625);
DISPLAY INVISIBLE (5675 2625);
FORCEPROP 1 LASTPIN (5625 2525) $PN 1
J 0
(5635 2505);
DISPLAY 0.489362 (5635 2505);
PAINT MONO (5635 2505);
FORCEPROP 1 LASTPIN (5625 2325) $PN 2
J 0
(5635 2305);
DISPLAY 0.489362 (5635 2305);
PAINT MONO (5635 2305);
FORCEPROP 1 LAST MATERIAL X6S
J 0
(5675 2375);
DISPLAY 0.489362 (5675 2375);
PAINT SKYBLUE (5675 2375);
FORCEPROP 1 LAST PACK_TYPE C0805
J 0
(5675 2325);
DISPLAY 0.489362 (5675 2325);
PAINT SKYBLUE (5675 2325);
FORCEPROP 1 LAST VALUE 22UF
J 0
(5675 2525);
DISPLAY 0.489362 (5675 2525);
PAINT SKYBLUE (5675 2525);
FORCEPROP 1 LAST VOLTAGE 16V
J 0
(5675 2475);
DISPLAY 0.489362 (5675 2475);
PAINT SKYBLUE (5675 2475);
FORCEPROP 1 LAST TOLERANCE 20%
J 0
(5675 2425);
DISPLAY 0.489362 (5675 2425);
PAINT SKYBLUE (5675 2425);
FORCEPROP 2 LAST CDS_LIB pure_quanta
J 0
(5625 2425);
DISPLAY INVISIBLE (5625 2425);
FORCEPROP 1 LAST PATH I49
J 0
(5675 2575);
DISPLAY 0.978723 (5675 2575);
PAINT WHITE (5675 2575);
DISPLAY INVISIBLE (5675 2575);
FORCEPROP 1 LAST PART_NUMBER CH6223MEA01
J 0
(5675 2275);
DISPLAY 0.489362 (5675 2275);
PAINT SKYBLUE (5675 2275);
DISPLAY INVISIBLE (5675 2275);
FORCEADD OFFPAGE..1
(1800 925);
FORCEPROP 2 LAST $XR0 200 
J 0
(1374 925);
DISPLAY 0.638298 (1374 925);
PAINT MONO (1374 925);
FORCEPROP 2 LAST CDS_LIB standard
J 0
(1800 925);
DISPLAY INVISIBLE (1800 925);
FORCEPROP 1 LAST OFFPAGE TRUE
J 0
(2125 800);
DISPLAY 0.872340 (2125 800);
PAINT GREEN (2125 800);
DISPLAY INVISIBLE (2125 800);
FORCEPROP 1 LAST COMMENT_BODY TRUE
J 0
(1925 825);
DISPLAY 0.872340 (1925 825);
PAINT GREEN (1925 825);
DISPLAY INVISIBLE (1925 825);
FORCEPROP 2 LAST PATH I5
J 0
(1550 975);
DISPLAY 0.680851 (1550 975);
DISPLAY INVISIBLE (1550 975);
FORCEADD VCC_CORE..1
(5625 2775);
FORCEPROP 3 LASTPIN (5625 2725) SIG_NAME SW_P12V_AUX_PVDDCR_CPU1_P0_FLT\g
J 0
(5635 2735);
DISPLAY 0.659574 (5635 2735);
PAINT MONO (5635 2735);
DISPLAY INVISIBLE (5635 2735);
FORCEPROP 1 LAST HDL_POWER SW_P12V_AUX_PVDDCR_CPU1_P0_FLT
J 1
(5625 2825);
DISPLAY 0.489362 (5625 2825);
PAINT GREEN (5625 2825);
FORCEPROP 2 LAST CDS_LIB pure_quanta_power
J 0
(5625 2775);
DISPLAY INVISIBLE (5625 2775);
FORCEPROP 1 LAST PATH I50
J 0
(5675 2800);
DISPLAY 0.872340 (5675 2800);
PAINT AQUA (5675 2800);
DISPLAY INVISIBLE (5675 2800);
FORCEADD Q_RES..1
(5850 3250);
FORCEPROP 1 LAST LOCATION PR92
J 0
(5825 3300);
DISPLAY 0.489362 (5825 3300);
PAINT SKYBLUE (5825 3300);
FORCEPROP 0 LAST $SEC 1
J 0
(6100 3400);
DISPLAY 0.680851 (6100 3400);
PAINT MONO (6100 3400);
DISPLAY INVISIBLE (6100 3400);
FORCEPROP 0 LAST CDS_SEC 1
J 0
(6100 3400);
DISPLAY 1.021277 (6100 3400);
DISPLAY INVISIBLE (6100 3400);
FORCEPROP 1 LASTPIN (5750 3250) $PN 1
J 0
(5740 3260);
DISPLAY 0.489362 (5740 3260);
PAINT MONO (5740 3260);
FORCEPROP 1 LASTPIN (5950 3250) $PN 2
J 0
(5912 3262);
DISPLAY 0.489362 (5912 3262);
PAINT MONO (5912 3262);
FORCEPROP 1 LAST WATTAGE 1/16W
J 2
(6100 3325);
DISPLAY 0.489362 (6100 3325);
PAINT SKYBLUE (6100 3325);
FORCEPROP 1 LAST MATERIAL CHIP
J 0
(6000 3275);
DISPLAY 0.489362 (6000 3275);
PAINT SKYBLUE (6000 3275);
FORCEPROP 1 LAST TOLERANCE 5%
J 0
(5675 3300);
DISPLAY 0.489362 (5675 3300);
PAINT SKYBLUE (5675 3300);
FORCEPROP 1 LAST VALUE 0
J 2
(5625 3300);
DISPLAY 0.489362 (5625 3300);
PAINT SKYBLUE (5625 3300);
FORCEPROP 1 LAST PACK_TYPE 0402LF
J 0
(5975 3200);
DISPLAY 0.489362 (5975 3200);
PAINT SKYBLUE (5975 3200);
FORCEPROP 2 LAST CDS_LIB pure_quanta
J 0
(5850 3250);
DISPLAY INVISIBLE (5850 3250);
FORCEPROP 1 LAST PATH I51
J 0
(5800 3400);
DISPLAY 0.978723 (5800 3400);
PAINT WHITE (5800 3400);
DISPLAY INVISIBLE (5800 3400);
FORCEPROP 1 LAST PART_NUMBER CS00002JB13
J 0
(5575 3200);
DISPLAY 0.489362 (5575 3200);
PAINT SKYBLUE (5575 3200);
DISPLAY INVISIBLE (5575 3200);
FORCEADD UNIVERSAL_GND..1
(6975 1075);
FORCEPROP 3 LASTPIN (6975 1125) SIG_NAME GND\g
J 0
(6985 1135);
DISPLAY 0.659574 (6985 1135);
PAINT MONO (6985 1135);
DISPLAY INVISIBLE (6985 1135);
FORCEPROP 2 LAST CDS_LIB pure_quanta_power
J 0
(6975 1075);
DISPLAY INVISIBLE (6975 1075);
FORCEPROP 1 LAST HDL_POWER GND
J 1
(7000 1000);
DISPLAY 0.872340 (7000 1000);
PAINT GREEN (7000 1000);
DISPLAY INVISIBLE (7000 1000);
FORCEPROP 1 LAST PATH I52
J 0
(7050 1075);
DISPLAY 0.872340 (7050 1075);
PAINT AQUA (7050 1075);
DISPLAY INVISIBLE (7050 1075);
FORCEADD UNIVERSAL_GND..1
(7925 900);
FORCEPROP 3 LASTPIN (7925 950) SIG_NAME GND\g
J 0
(7935 960);
DISPLAY 0.659574 (7935 960);
PAINT MONO (7935 960);
DISPLAY INVISIBLE (7935 960);
FORCEPROP 2 LAST CDS_LIB pure_quanta_power
J 0
(7925 900);
PAINT MONO (7925 900);
DISPLAY INVISIBLE (7925 900);
FORCEPROP 1 LAST HDL_POWER GND
J 1
(7950 825);
DISPLAY 0.872340 (7950 825);
PAINT GREEN (7950 825);
DISPLAY INVISIBLE (7950 825);
FORCEPROP 1 LAST PATH I53
J 0
(8000 900);
DISPLAY 0.872340 (8000 900);
PAINT AQUA (8000 900);
DISPLAY INVISIBLE (8000 900);
FORCEADD Q_CAP..1
(7500 1325);
FORCEPROP 1 LAST LOCATION PC127_4
J 0
(7550 1450);
DISPLAY 0.489362 (7550 1450);
PAINT SKYBLUE (7550 1450);
FORCEPROP 0 LAST $SEC 1
J 0
(7550 1500);
DISPLAY 0.680851 (7550 1500);
PAINT MONO (7550 1500);
DISPLAY INVISIBLE (7550 1500);
FORCEPROP 0 LAST CDS_SEC 1
J 0
(7550 1500);
DISPLAY 1.021277 (7550 1500);
DISPLAY INVISIBLE (7550 1500);
FORCEPROP 1 LASTPIN (7500 1425) $PN 1
J 0
(7510 1405);
DISPLAY 0.489362 (7510 1405);
PAINT MONO (7510 1405);
FORCEPROP 1 LASTPIN (7500 1225) $PN 2
J 0
(7510 1205);
DISPLAY 0.489362 (7510 1205);
PAINT MONO (7510 1205);
FORCEPROP 1 LAST MATERIAL X6S
J 0
(7550 1250);
DISPLAY 0.489362 (7550 1250);
PAINT SKYBLUE (7550 1250);
FORCEPROP 1 LAST TOLERANCE 20%
J 0
(7550 1300);
DISPLAY 0.489362 (7550 1300);
PAINT SKYBLUE (7550 1300);
FORCEPROP 1 LAST VALUE 22UF
J 0
(7550 1400);
DISPLAY 0.489362 (7550 1400);
PAINT SKYBLUE (7550 1400);
FORCEPROP 1 LAST VOLTAGE 4V
J 0
(7550 1350);
DISPLAY 0.489362 (7550 1350);
PAINT SKYBLUE (7550 1350);
FORCEPROP 1 LAST PACK_TYPE C0805
J 0
(7550 1200);
DISPLAY 0.489362 (7550 1200);
PAINT SKYBLUE (7550 1200);
FORCEPROP 2 LAST CDS_LIB pure_quanta
J 0
(7500 1325);
DISPLAY INVISIBLE (7500 1325);
FORCEPROP 1 LAST PATH I54
J 0
(7550 1475);
DISPLAY 0.978723 (7550 1475);
PAINT WHITE (7550 1475);
DISPLAY INVISIBLE (7550 1475);
FORCEPROP 1 LAST PART_NUMBER CH622KMEA03
J 0
(7550 1150);
DISPLAY 0.489362 (7550 1150);
PAINT SKYBLUE (7550 1150);
DISPLAY INVISIBLE (7550 1150);
FORCEADD Q_CAP..1
(7925 1325);
FORCEPROP 1 LAST LOCATION PC128_4
J 0
(7975 1450);
DISPLAY 0.489362 (7975 1450);
PAINT SKYBLUE (7975 1450);
FORCEPROP 0 LAST $SEC 1
J 0
(7975 1500);
DISPLAY 0.680851 (7975 1500);
PAINT MONO (7975 1500);
DISPLAY INVISIBLE (7975 1500);
FORCEPROP 0 LAST CDS_SEC 1
J 0
(7975 1500);
DISPLAY 1.021277 (7975 1500);
DISPLAY INVISIBLE (7975 1500);
FORCEPROP 1 LASTPIN (7925 1425) $PN 1
J 0
(7935 1405);
DISPLAY 0.489362 (7935 1405);
PAINT MONO (7935 1405);
FORCEPROP 1 LASTPIN (7925 1225) $PN 2
J 0
(7935 1205);
DISPLAY 0.489362 (7935 1205);
PAINT MONO (7935 1205);
FORCEPROP 1 LAST MATERIAL X6S
J 0
(7975 1250);
DISPLAY 0.489362 (7975 1250);
PAINT SKYBLUE (7975 1250);
FORCEPROP 1 LAST TOLERANCE 20%
J 0
(7975 1300);
DISPLAY 0.489362 (7975 1300);
PAINT SKYBLUE (7975 1300);
FORCEPROP 1 LAST VALUE 22UF
J 0
(7975 1400);
DISPLAY 0.489362 (7975 1400);
PAINT SKYBLUE (7975 1400);
FORCEPROP 1 LAST VOLTAGE 4V
J 0
(7975 1350);
DISPLAY 0.489362 (7975 1350);
PAINT SKYBLUE (7975 1350);
FORCEPROP 1 LAST PACK_TYPE C0805
J 0
(7975 1200);
DISPLAY 0.489362 (7975 1200);
PAINT SKYBLUE (7975 1200);
FORCEPROP 2 LAST CDS_LIB pure_quanta
J 0
(7925 1325);
DISPLAY INVISIBLE (7925 1325);
FORCEPROP 1 LAST PATH I55
J 0
(7975 1475);
DISPLAY 0.978723 (7975 1475);
PAINT WHITE (7975 1475);
DISPLAY INVISIBLE (7975 1475);
FORCEPROP 1 LAST PART_NUMBER CH622KMEA03
J 0
(7975 1150);
DISPLAY 0.489362 (7975 1150);
PAINT SKYBLUE (7975 1150);
DISPLAY INVISIBLE (7975 1150);
FORCEADD VCC_CORE..1
(7925 1625);
FORCEPROP 3 LASTPIN (7925 1575) SIG_NAME PVDDCR_CPU1_P0\g
J 0
(7935 1585);
DISPLAY 0.659574 (7935 1585);
PAINT MONO (7935 1585);
DISPLAY INVISIBLE (7935 1585);
FORCEPROP 1 LAST HDL_POWER PVDDCR_CPU1_P0
J 1
(7925 1675);
DISPLAY 0.489362 (7925 1675);
PAINT GREEN (7925 1675);
FORCEPROP 2 LAST CDS_LIB pure_quanta_power
J 0
(7925 1625);
DISPLAY INVISIBLE (7925 1625);
FORCEPROP 1 LAST PATH I56
J 0
(7975 1650);
DISPLAY 0.872340 (7975 1650);
PAINT AQUA (7975 1650);
DISPLAY INVISIBLE (7975 1650);
FORCEADD Q_RES..1
(4525 4700);
FORCEPROP 1 LAST LOCATION PR90
J 0
(4300 4775);
DISPLAY 0.489362 (4300 4775);
PAINT SKYBLUE (4300 4775);
FORCEPROP 0 LAST $SEC 1
J 0
(4800 4800);
DISPLAY 0.680851 (4800 4800);
PAINT MONO (4800 4800);
DISPLAY INVISIBLE (4800 4800);
FORCEPROP 0 LAST CDS_SEC 1
J 0
(4800 4800);
DISPLAY 1.021277 (4800 4800);
DISPLAY INVISIBLE (4800 4800);
FORCEPROP 1 LASTPIN (4425 4700) $PN 1
J 0
(4437 4712);
DISPLAY 0.787234 (4437 4712);
PAINT MONO (4437 4712);
DISPLAY INVISIBLE (4437 4712);
FORCEPROP 1 LASTPIN (4625 4700) $PN 2
J 0
(4587 4712);
DISPLAY 0.787234 (4587 4712);
PAINT MONO (4587 4712);
DISPLAY INVISIBLE (4587 4712);
FORCEPROP 1 LAST TOLERANCE 1%
J 0
(4525 4775);
DISPLAY 0.489362 (4525 4775);
PAINT SKYBLUE (4525 4775);
FORCEPROP 1 LAST WATTAGE 1/16W
J 2
(4800 4775);
DISPLAY 0.489362 (4800 4775);
PAINT SKYBLUE (4800 4775);
FORCEPROP 1 LAST PACK_TYPE 0402LF
J 0
(4925 4625);
DISPLAY 0.489362 (4925 4625);
PAINT SKYBLUE (4925 4625);
FORCEPROP 1 LAST VALUE 5.6
J 2
(4475 4775);
DISPLAY 0.489362 (4475 4775);
PAINT SKYBLUE (4475 4775);
FORCEPROP 1 LAST MATERIAL CHIP
J 0
(4375 4625);
DISPLAY 0.489362 (4375 4625);
PAINT SKYBLUE (4375 4625);
FORCEPROP 2 LAST CDS_LIB pure_quanta
J 0
(4525 4700);
DISPLAY INVISIBLE (4525 4700);
FORCEPROP 1 LAST PATH I57
J 0
(4475 4850);
DISPLAY 0.978723 (4475 4850);
PAINT WHITE (4475 4850);
DISPLAY INVISIBLE (4475 4850);
FORCEPROP 1 LAST PART_NUMBER CS-5602FB01
J 0
(4550 4625);
DISPLAY 0.489362 (4550 4625);
PAINT SKYBLUE (4550 4625);
DISPLAY INVISIBLE (4550 4625);
FORCEADD Q_CAP..1
(4700 4150);
FORCEPROP 1 LAST LOCATION PC192
J 0
(4750 4250);
DISPLAY 0.489362 (4750 4250);
PAINT SKYBLUE (4750 4250);
FORCEPROP 0 LAST $SEC 1
J 0
(4750 4300);
DISPLAY 0.680851 (4750 4300);
PAINT MONO (4750 4300);
DISPLAY INVISIBLE (4750 4300);
FORCEPROP 0 LAST CDS_SEC 1
J 0
(4750 4300);
DISPLAY 1.021277 (4750 4300);
DISPLAY INVISIBLE (4750 4300);
FORCEPROP 1 LASTPIN (4700 4250) $PN 1
J 0
(4710 4230);
DISPLAY 0.489362 (4710 4230);
PAINT MONO (4710 4230);
FORCEPROP 1 LASTPIN (4700 4050) $PN 2
J 0
(4710 4030);
DISPLAY 0.489362 (4710 4030);
PAINT MONO (4710 4030);
FORCEPROP 1 LAST PACK_TYPE C0402
J 0
(4750 3950);
DISPLAY 0.489362 (4750 3950);
PAINT SKYBLUE (4750 3950);
FORCEPROP 1 LAST VOLTAGE 50V
J 0
(4750 4150);
DISPLAY 0.489362 (4750 4150);
PAINT SKYBLUE (4750 4150);
FORCEPROP 1 LAST VALUE 560PF
J 0
(4750 4200);
DISPLAY 0.489362 (4750 4200);
PAINT SKYBLUE (4750 4200);
FORCEPROP 1 LAST TOLERANCE 10%
J 0
(4750 4100);
DISPLAY 0.489362 (4750 4100);
PAINT SKYBLUE (4750 4100);
FORCEPROP 1 LAST MATERIAL EMPTY
J 0
(4750 4050);
DISPLAY 0.489362 (4750 4050);
PAINT RED (4750 4050);
FORCEPROP 2 LAST CDS_LIB pure_quanta
J 0
(4700 4150);
DISPLAY INVISIBLE (4700 4150);
FORCEPROP 1 LAST PATH I58
J 0
(4750 4300);
DISPLAY 0.978723 (4750 4300);
PAINT WHITE (4750 4300);
DISPLAY INVISIBLE (4750 4300);
FORCEPROP 1 LAST PART_NUMBER CH1566K1B09
J 0
(4750 4000);
DISPLAY 0.489362 (4750 4000);
PAINT SKYBLUE (4750 4000);
DISPLAY INVISIBLE (4750 4000);
FORCEADD OFFPAGE..6
(5250 4100);
FORCEPROP 2 LAST $XR0 201 
J 0
(4970 4100);
DISPLAY 0.638298 (4970 4100);
PAINT MONO (4970 4100);
FORCEPROP 2 LAST CDS_LIB standard
J 0
(5250 4100);
DISPLAY INVISIBLE (5250 4100);
FORCEPROP 1 LAST OFFPAGE TRUE
J 0
(5575 3975);
DISPLAY 0.872340 (5575 3975);
PAINT GREEN (5575 3975);
DISPLAY INVISIBLE (5575 3975);
FORCEPROP 1 LAST COMMENT_BODY TRUE
J 0
(5350 4025);
DISPLAY 0.872340 (5350 4025);
PAINT GREEN (5350 4025);
DISPLAY INVISIBLE (5350 4025);
FORCEPROP 2 LAST PATH I59
J 0
(4950 4150);
DISPLAY 0.680851 (4950 4150);
DISPLAY INVISIBLE (4950 4150);
FORCEADD UNIVERSAL_GND..1
(1475 1775);
FORCEPROP 3 LASTPIN (1475 1825) SIG_NAME GND\g
J 0
(1485 1835);
DISPLAY 0.659574 (1485 1835);
PAINT MONO (1485 1835);
DISPLAY INVISIBLE (1485 1835);
FORCEPROP 2 LAST CDS_LIB pure_quanta_power
J 0
(1475 1775);
DISPLAY INVISIBLE (1475 1775);
FORCEPROP 1 LAST HDL_POWER GND
J 1
(1500 1700);
DISPLAY 0.872340 (1500 1700);
PAINT GREEN (1500 1700);
DISPLAY INVISIBLE (1500 1700);
FORCEPROP 1 LAST PATH I6
J 0
(1550 1775);
DISPLAY 0.872340 (1550 1775);
PAINT AQUA (1550 1775);
DISPLAY INVISIBLE (1550 1775);
FORCEADD Q_CAP..1
(4500 5275);
FORCEPROP 1 LAST LOCATION PC118_3
J 0
(4550 5425);
DISPLAY 0.489362 (4550 5425);
PAINT SKYBLUE (4550 5425);
FORCEPROP 0 LAST $SEC 1
J 0
(4550 5475);
DISPLAY 0.680851 (4550 5475);
PAINT MONO (4550 5475);
DISPLAY INVISIBLE (4550 5475);
FORCEPROP 0 LAST CDS_SEC 1
J 0
(4550 5475);
DISPLAY 1.021277 (4550 5475);
DISPLAY INVISIBLE (4550 5475);
FORCEPROP 1 LASTPIN (4500 5375) $PN 1
J 0
(4510 5355);
DISPLAY 0.489362 (4510 5355);
PAINT MONO (4510 5355);
FORCEPROP 1 LASTPIN (4500 5175) $PN 2
J 0
(4510 5155);
DISPLAY 0.489362 (4510 5155);
PAINT MONO (4510 5155);
FORCEPROP 1 LAST MATERIAL X6S
J 0
(4550 5225);
DISPLAY 0.489362 (4550 5225);
PAINT SKYBLUE (4550 5225);
FORCEPROP 1 LAST VALUE 1UF
J 0
(4550 5375);
DISPLAY 0.489362 (4550 5375);
PAINT SKYBLUE (4550 5375);
FORCEPROP 1 LAST VOLTAGE 25V
J 0
(4550 5325);
DISPLAY 0.489362 (4550 5325);
PAINT SKYBLUE (4550 5325);
FORCEPROP 1 LAST TOLERANCE 10%
J 0
(4550 5275);
DISPLAY 0.489362 (4550 5275);
PAINT SKYBLUE (4550 5275);
FORCEPROP 1 LAST PACK_TYPE C0402
J 0
(4550 5175);
DISPLAY 0.489362 (4550 5175);
PAINT SKYBLUE (4550 5175);
FORCEPROP 2 LAST CDS_LIB pure_quanta
J 0
(4500 5275);
DISPLAY INVISIBLE (4500 5275);
FORCEPROP 1 LAST PATH I60
J 0
(4550 5425);
DISPLAY 0.978723 (4550 5425);
PAINT WHITE (4550 5425);
DISPLAY INVISIBLE (4550 5425);
FORCEPROP 1 LAST PART_NUMBER CH5104KEB02
J 0
(4550 5125);
DISPLAY 0.489362 (4550 5125);
PAINT SKYBLUE (4550 5125);
DISPLAY INVISIBLE (4550 5125);
FORCEADD Q_CAP..1
(4900 5275);
FORCEPROP 1 LAST LOCATION PC120_3
J 0
(4950 5425);
DISPLAY 0.489362 (4950 5425);
PAINT SKYBLUE (4950 5425);
FORCEPROP 0 LAST $SEC 1
J 0
(4950 5475);
DISPLAY 0.680851 (4950 5475);
PAINT MONO (4950 5475);
DISPLAY INVISIBLE (4950 5475);
FORCEPROP 0 LAST CDS_SEC 1
J 0
(4950 5475);
DISPLAY 1.021277 (4950 5475);
DISPLAY INVISIBLE (4950 5475);
FORCEPROP 1 LASTPIN (4900 5375) $PN 1
J 0
(4910 5355);
DISPLAY 0.489362 (4910 5355);
PAINT MONO (4910 5355);
FORCEPROP 1 LASTPIN (4900 5175) $PN 2
J 0
(4910 5155);
DISPLAY 0.489362 (4910 5155);
PAINT MONO (4910 5155);
FORCEPROP 1 LAST MATERIAL X6S
J 0
(4950 5225);
DISPLAY 0.489362 (4950 5225);
PAINT SKYBLUE (4950 5225);
FORCEPROP 1 LAST PACK_TYPE C0805
J 0
(4950 5175);
DISPLAY 0.489362 (4950 5175);
PAINT SKYBLUE (4950 5175);
FORCEPROP 1 LAST VALUE 22UF
J 0
(4950 5375);
DISPLAY 0.489362 (4950 5375);
PAINT SKYBLUE (4950 5375);
FORCEPROP 1 LAST VOLTAGE 16V
J 0
(4950 5325);
DISPLAY 0.489362 (4950 5325);
PAINT SKYBLUE (4950 5325);
FORCEPROP 1 LAST TOLERANCE 20%
J 0
(4950 5275);
DISPLAY 0.489362 (4950 5275);
PAINT SKYBLUE (4950 5275);
FORCEPROP 2 LAST CDS_LIB pure_quanta
J 0
(4900 5275);
DISPLAY INVISIBLE (4900 5275);
FORCEPROP 1 LAST PATH I61
J 0
(4950 5425);
DISPLAY 0.978723 (4950 5425);
PAINT WHITE (4950 5425);
DISPLAY INVISIBLE (4950 5425);
FORCEPROP 1 LAST PART_NUMBER CH6223MEA01
J 0
(4950 5125);
DISPLAY 0.489362 (4950 5125);
PAINT SKYBLUE (4950 5125);
DISPLAY INVISIBLE (4950 5125);
FORCEADD Q_CAP..1
(5250 4575);
FORCEPROP 1 LAST LOCATION PC122
J 0
(5300 4675);
DISPLAY 0.489362 (5300 4675);
PAINT SKYBLUE (5300 4675);
FORCEPROP 0 LAST $SEC 1
J 0
(5300 4725);
DISPLAY 0.680851 (5300 4725);
PAINT MONO (5300 4725);
DISPLAY INVISIBLE (5300 4725);
FORCEPROP 0 LAST CDS_SEC 1
J 2
(5300 4700);
DISPLAY 1.021277 (5300 4700);
DISPLAY INVISIBLE (5300 4700);
FORCEPROP 1 LASTPIN (5250 4675) $PN 1
J 0
(5260 4655);
DISPLAY 0.489362 (5260 4655);
PAINT MONO (5260 4655);
FORCEPROP 1 LASTPIN (5250 4475) $PN 2
J 0
(5260 4455);
DISPLAY 0.489362 (5260 4455);
PAINT MONO (5260 4455);
FORCEPROP 1 LAST MATERIAL X7R
J 0
(5300 4475);
DISPLAY 0.489362 (5300 4475);
PAINT SKYBLUE (5300 4475);
FORCEPROP 1 LAST PACK_TYPE 0402
J 0
(5300 4375);
DISPLAY 0.489362 (5300 4375);
PAINT SKYBLUE (5300 4375);
FORCEPROP 1 LAST VOLTAGE 16V
J 0
(5300 4575);
DISPLAY 0.489362 (5300 4575);
PAINT SKYBLUE (5300 4575);
FORCEPROP 1 LAST TOLERANCE 10%
J 0
(5300 4525);
DISPLAY 0.489362 (5300 4525);
PAINT SKYBLUE (5300 4525);
FORCEPROP 1 LAST VALUE 0.22UF
J 0
(5300 4625);
DISPLAY 0.489362 (5300 4625);
PAINT SKYBLUE (5300 4625);
FORCEPROP 2 LAST CDS_LIB pure_quanta
J 2
(5250 4575);
DISPLAY INVISIBLE (5250 4575);
FORCEPROP 1 LAST PATH I62
J 0
(5300 4725);
DISPLAY 0.978723 (5300 4725);
PAINT WHITE (5300 4725);
DISPLAY INVISIBLE (5300 4725);
FORCEPROP 1 LAST PART_NUMBER CH4223K1B00
J 0
(5300 4425);
DISPLAY 0.489362 (5300 4425);
PAINT SKYBLUE (5300 4425);
DISPLAY INVISIBLE (5300 4425);
FORCEADD UNIVERSAL_GND..1
(5675 4925);
FORCEPROP 3 LASTPIN (5675 4975) SIG_NAME GND\g
J 0
(5685 4985);
DISPLAY 0.659574 (5685 4985);
PAINT MONO (5685 4985);
DISPLAY INVISIBLE (5685 4985);
FORCEPROP 2 LAST CDS_LIB pure_quanta_power
J 0
(5675 4925);
PAINT MONO (5675 4925);
DISPLAY INVISIBLE (5675 4925);
FORCEPROP 1 LAST HDL_POWER GND
J 1
(5700 4850);
DISPLAY 0.872340 (5700 4850);
PAINT GREEN (5700 4850);
DISPLAY INVISIBLE (5700 4850);
FORCEPROP 1 LAST PATH I63
J 0
(5750 4925);
DISPLAY 0.872340 (5750 4925);
PAINT AQUA (5750 4925);
DISPLAY INVISIBLE (5750 4925);
FORCEADD Q_INDUCTOR4P_14..1
(6475 4225);
FORCEPROP 1 LAST LOCATION PL14
J 0
(6250 4480);
DISPLAY 0.489362 (6250 4480);
PAINT SKYBLUE (6250 4480);
FORCEPROP 0 LAST $SEC 1
J 0
(6250 4525);
DISPLAY 0.680851 (6250 4525);
PAINT MONO (6250 4525);
DISPLAY INVISIBLE (6250 4525);
FORCEPROP 0 LAST CDS_SEC 1
J 0
(6250 4525);
DISPLAY 1.021277 (6250 4525);
DISPLAY INVISIBLE (6250 4525);
FORCEPROP 0 LASTPIN (6075 4350) $PN 1
J 2
(6065 4360);
DISPLAY 0.489362 (6065 4360);
PAINT MONO (6065 4360);
FORCEPROP 0 LASTPIN (6075 4100) $PN 2
J 2
(6065 4110);
DISPLAY 0.489362 (6065 4110);
PAINT MONO (6065 4110);
FORCEPROP 0 LASTPIN (6875 4100) $PN 3
J 0
(6885 4110);
DISPLAY 0.489362 (6885 4110);
PAINT MONO (6885 4110);
FORCEPROP 0 LASTPIN (6875 4350) $PN 4
J 0
(6885 4360);
DISPLAY 0.489362 (6885 4360);
PAINT MONO (6885 4360);
FORCEPROP 2 LAST VALUE 150NH
J 0
(6375 4400);
DISPLAY 0.489362 (6375 4400);
PAINT SKYBLUE (6375 4400);
FORCEPROP 1 LAST MATERIAL IND
J 0
(6275 4400);
DISPLAY 0.489362 (6275 4400);
PAINT SKYBLUE (6275 4400);
FORCEPROP 2 LAST PART_TYPE SMLF
J 0
(6400 3975);
DISPLAY 1.021277 (6400 3975);
FORCEPROP 1 LAST NEEDS_NO_SIZE TRUE
J 0
(6475 4225);
DISPLAY 0.468085 (6475 4225);
PAINT GREEN (6475 4225);
DISPLAY INVISIBLE (6475 4225);
FORCEPROP 2 LAST CDS_LIB pure_quanta
J 0
(6475 4225);
DISPLAY INVISIBLE (6475 4225);
FORCEPROP 1 LAST PATH I64
J 0
(6675 4380);
DISPLAY 0.723404 (6675 4380);
PAINT GREEN (6675 4380);
DISPLAY INVISIBLE (6675 4380);
FORCEPROP 1 LAST PART_NUMBER CV+15^0TZ04
J 0
(6525 4400);
DISPLAY 0.489362 (6525 4400);
PAINT SKYBLUE (6525 4400);
DISPLAY INVISIBLE (6525 4400);
FORCEADD Q_CAP..1
(5300 5275);
FORCEPROP 1 LAST LOCATION PC124_3
J 0
(5350 5425);
DISPLAY 0.489362 (5350 5425);
PAINT SKYBLUE (5350 5425);
FORCEPROP 0 LAST $SEC 1
J 0
(5350 5475);
DISPLAY 0.680851 (5350 5475);
PAINT MONO (5350 5475);
DISPLAY INVISIBLE (5350 5475);
FORCEPROP 0 LAST CDS_SEC 1
J 0
(5350 5475);
DISPLAY 1.021277 (5350 5475);
DISPLAY INVISIBLE (5350 5475);
FORCEPROP 1 LASTPIN (5300 5375) $PN 1
J 0
(5310 5355);
DISPLAY 0.489362 (5310 5355);
PAINT MONO (5310 5355);
FORCEPROP 1 LASTPIN (5300 5175) $PN 2
J 0
(5310 5155);
DISPLAY 0.489362 (5310 5155);
PAINT MONO (5310 5155);
FORCEPROP 1 LAST MATERIAL X6S
J 0
(5350 5225);
DISPLAY 0.489362 (5350 5225);
PAINT SKYBLUE (5350 5225);
FORCEPROP 1 LAST PACK_TYPE C0805
J 0
(5350 5175);
DISPLAY 0.489362 (5350 5175);
PAINT SKYBLUE (5350 5175);
FORCEPROP 1 LAST VALUE 22UF
J 0
(5350 5375);
DISPLAY 0.489362 (5350 5375);
PAINT SKYBLUE (5350 5375);
FORCEPROP 1 LAST VOLTAGE 16V
J 0
(5350 5325);
DISPLAY 0.489362 (5350 5325);
PAINT SKYBLUE (5350 5325);
FORCEPROP 1 LAST TOLERANCE 20%
J 0
(5350 5275);
DISPLAY 0.489362 (5350 5275);
PAINT SKYBLUE (5350 5275);
FORCEPROP 2 LAST CDS_LIB pure_quanta
J 0
(5300 5275);
DISPLAY INVISIBLE (5300 5275);
FORCEPROP 1 LAST PATH I65
J 0
(5350 5425);
DISPLAY 0.978723 (5350 5425);
PAINT WHITE (5350 5425);
DISPLAY INVISIBLE (5350 5425);
FORCEPROP 1 LAST PART_NUMBER CH6223MEA01
J 0
(5350 5125);
DISPLAY 0.489362 (5350 5125);
PAINT SKYBLUE (5350 5125);
DISPLAY INVISIBLE (5350 5125);
FORCEADD Q_CAP..1
(5675 5275);
FORCEPROP 1 LAST LOCATION PC126_3
J 0
(5725 5425);
DISPLAY 0.489362 (5725 5425);
PAINT SKYBLUE (5725 5425);
FORCEPROP 0 LAST $SEC 1
J 0
(5725 5475);
DISPLAY 0.680851 (5725 5475);
PAINT MONO (5725 5475);
DISPLAY INVISIBLE (5725 5475);
FORCEPROP 0 LAST CDS_SEC 1
J 0
(5725 5475);
DISPLAY 1.021277 (5725 5475);
DISPLAY INVISIBLE (5725 5475);
FORCEPROP 1 LASTPIN (5675 5375) $PN 1
J 0
(5685 5355);
DISPLAY 0.489362 (5685 5355);
PAINT MONO (5685 5355);
FORCEPROP 1 LASTPIN (5675 5175) $PN 2
J 0
(5685 5155);
DISPLAY 0.489362 (5685 5155);
PAINT MONO (5685 5155);
FORCEPROP 1 LAST MATERIAL X6S
J 0
(5725 5225);
DISPLAY 0.489362 (5725 5225);
PAINT SKYBLUE (5725 5225);
FORCEPROP 1 LAST PACK_TYPE C0805
J 0
(5725 5175);
DISPLAY 0.489362 (5725 5175);
PAINT SKYBLUE (5725 5175);
FORCEPROP 1 LAST VALUE 22UF
J 0
(5725 5375);
DISPLAY 0.489362 (5725 5375);
PAINT SKYBLUE (5725 5375);
FORCEPROP 1 LAST VOLTAGE 16V
J 0
(5725 5325);
DISPLAY 0.489362 (5725 5325);
PAINT SKYBLUE (5725 5325);
FORCEPROP 1 LAST TOLERANCE 20%
J 0
(5725 5275);
DISPLAY 0.489362 (5725 5275);
PAINT SKYBLUE (5725 5275);
FORCEPROP 2 LAST CDS_LIB pure_quanta
J 0
(5675 5275);
DISPLAY INVISIBLE (5675 5275);
FORCEPROP 1 LAST PATH I66
J 0
(5725 5425);
DISPLAY 0.978723 (5725 5425);
PAINT WHITE (5725 5425);
DISPLAY INVISIBLE (5725 5425);
FORCEPROP 1 LAST PART_NUMBER CH6223MEA01
J 0
(5725 5125);
DISPLAY 0.489362 (5725 5125);
PAINT SKYBLUE (5725 5125);
DISPLAY INVISIBLE (5725 5125);
FORCEADD VCC_CORE..1
(5675 5625);
FORCEPROP 3 LASTPIN (5675 5575) SIG_NAME SW_P12V_AUX_PVDDCR_CPU1_P0_FLT\g
J 0
(5685 5585);
DISPLAY 0.659574 (5685 5585);
PAINT MONO (5685 5585);
DISPLAY INVISIBLE (5685 5585);
FORCEPROP 1 LAST HDL_POWER SW_P12V_AUX_PVDDCR_CPU1_P0_FLT
J 1
(5675 5675);
DISPLAY 0.489362 (5675 5675);
PAINT GREEN (5675 5675);
FORCEPROP 2 LAST CDS_LIB pure_quanta_power
J 0
(5675 5625);
DISPLAY INVISIBLE (5675 5625);
FORCEPROP 1 LAST PATH I67
J 0
(5725 5650);
DISPLAY 0.872340 (5725 5650);
PAINT AQUA (5725 5650);
DISPLAY INVISIBLE (5725 5650);
FORCEADD OFFPAGE..3
(7425 4100);
FORCEPROP 2 LAST $XR0 202 
J 0
(7759 4100);
DISPLAY 0.638298 (7759 4100);
PAINT MONO (7759 4100);
FORCEPROP 2 LAST CDS_LIB standard
J 0
(7425 4100);
DISPLAY INVISIBLE (7425 4100);
FORCEPROP 1 LAST OFFPAGE TRUE
J 0
(7750 3975);
DISPLAY 0.872340 (7750 3975);
PAINT GREEN (7750 3975);
DISPLAY INVISIBLE (7750 3975);
FORCEPROP 1 LAST COMMENT_BODY TRUE
J 0
(7375 4000);
DISPLAY 0.872340 (7375 4000);
PAINT GREEN (7375 4000);
DISPLAY INVISIBLE (7375 4000);
FORCEPROP 2 LAST PATH I68
J 0
(7775 4150);
DISPLAY 0.680851 (7775 4150);
DISPLAY INVISIBLE (7775 4150);
FORCEADD Q_CAP..1
(7950 4150);
FORCEPROP 1 LAST LOCATION PC129_3
J 0
(8000 4275);
DISPLAY 0.489362 (8000 4275);
PAINT SKYBLUE (8000 4275);
FORCEPROP 0 LAST $SEC 1
J 0
(8000 4325);
DISPLAY 0.680851 (8000 4325);
PAINT MONO (8000 4325);
DISPLAY INVISIBLE (8000 4325);
FORCEPROP 0 LAST CDS_SEC 1
J 0
(8000 4325);
DISPLAY 1.021277 (8000 4325);
DISPLAY INVISIBLE (8000 4325);
FORCEPROP 1 LASTPIN (7950 4250) $PN 1
J 0
(7960 4230);
DISPLAY 0.489362 (7960 4230);
PAINT MONO (7960 4230);
FORCEPROP 1 LASTPIN (7950 4050) $PN 2
J 0
(7960 4030);
DISPLAY 0.489362 (7960 4030);
PAINT MONO (7960 4030);
FORCEPROP 1 LAST MATERIAL X6S
J 0
(8000 4075);
DISPLAY 0.489362 (8000 4075);
PAINT SKYBLUE (8000 4075);
FORCEPROP 1 LAST TOLERANCE 20%
J 0
(8000 4125);
DISPLAY 0.489362 (8000 4125);
PAINT SKYBLUE (8000 4125);
FORCEPROP 1 LAST VALUE 22UF
J 0
(8000 4225);
DISPLAY 0.489362 (8000 4225);
PAINT SKYBLUE (8000 4225);
FORCEPROP 1 LAST VOLTAGE 4V
J 0
(8000 4175);
DISPLAY 0.489362 (8000 4175);
PAINT SKYBLUE (8000 4175);
FORCEPROP 1 LAST PACK_TYPE C0805
J 0
(8000 4025);
DISPLAY 0.489362 (8000 4025);
PAINT SKYBLUE (8000 4025);
FORCEPROP 2 LAST CDS_LIB pure_quanta
J 0
(7950 4150);
DISPLAY INVISIBLE (7950 4150);
FORCEPROP 1 LAST PATH I69
J 0
(8000 4300);
DISPLAY 0.978723 (8000 4300);
PAINT WHITE (8000 4300);
DISPLAY INVISIBLE (8000 4300);
FORCEPROP 1 LAST PART_NUMBER CH622KMEA03
J 0
(8000 3975);
DISPLAY 0.489362 (8000 3975);
PAINT SKYBLUE (8000 3975);
DISPLAY INVISIBLE (8000 3975);
FORCEADD Q_CAP..1
(1475 1975);
FORCEPROP 1 LAST LOCATION PC109
J 0
(1525 2075);
DISPLAY 0.489362 (1525 2075);
PAINT SKYBLUE (1525 2075);
FORCEPROP 0 LAST $SEC 1
J 0
(1525 2125);
DISPLAY 0.680851 (1525 2125);
PAINT MONO (1525 2125);
DISPLAY INVISIBLE (1525 2125);
FORCEPROP 0 LAST CDS_SEC 1
J 0
(1525 2125);
DISPLAY 1.021277 (1525 2125);
DISPLAY INVISIBLE (1525 2125);
FORCEPROP 1 LASTPIN (1475 2075) $PN 1
J 0
(1485 2055);
DISPLAY 0.489362 (1485 2055);
PAINT MONO (1485 2055);
FORCEPROP 1 LASTPIN (1475 1875) $PN 2
J 0
(1485 1855);
DISPLAY 0.489362 (1485 1855);
PAINT MONO (1485 1855);
FORCEPROP 1 LAST PACK_TYPE C0402
J 0
(1525 1775);
DISPLAY 0.489362 (1525 1775);
PAINT SKYBLUE (1525 1775);
FORCEPROP 1 LAST VOLTAGE 10V
J 0
(1525 1975);
DISPLAY 0.489362 (1525 1975);
PAINT SKYBLUE (1525 1975);
FORCEPROP 1 LAST VALUE 2.2UF
J 0
(1525 2025);
DISPLAY 0.489362 (1525 2025);
PAINT SKYBLUE (1525 2025);
FORCEPROP 1 LAST TOLERANCE 10%
J 0
(1525 1925);
DISPLAY 0.489362 (1525 1925);
PAINT SKYBLUE (1525 1925);
FORCEPROP 1 LAST MATERIAL X6S
J 0
(1525 1875);
DISPLAY 0.489362 (1525 1875);
PAINT SKYBLUE (1525 1875);
FORCEPROP 2 LAST CDS_LIB pure_quanta
J 0
(1475 1975);
DISPLAY INVISIBLE (1475 1975);
FORCEPROP 1 LAST PATH I7
J 0
(1525 2125);
DISPLAY 0.978723 (1525 2125);
PAINT WHITE (1525 2125);
DISPLAY INVISIBLE (1525 2125);
FORCEPROP 1 LAST PART_NUMBER CH5222KEB01
J 0
(1525 1825);
DISPLAY 0.489362 (1525 1825);
PAINT SKYBLUE (1525 1825);
DISPLAY INVISIBLE (1525 1825);
FORCEADD UNIVERSAL_GND..1
(8375 3825);
FORCEPROP 3 LASTPIN (8375 3875) SIG_NAME GND\g
J 0
(8385 3885);
DISPLAY 0.659574 (8385 3885);
PAINT MONO (8385 3885);
DISPLAY INVISIBLE (8385 3885);
FORCEPROP 2 LAST CDS_LIB pure_quanta_power
J 0
(8375 3825);
PAINT MONO (8375 3825);
DISPLAY INVISIBLE (8375 3825);
FORCEPROP 1 LAST HDL_POWER GND
J 1
(8400 3750);
DISPLAY 0.872340 (8400 3750);
PAINT GREEN (8400 3750);
DISPLAY INVISIBLE (8400 3750);
FORCEPROP 1 LAST PATH I70
J 0
(8450 3825);
DISPLAY 0.872340 (8450 3825);
PAINT AQUA (8450 3825);
DISPLAY INVISIBLE (8450 3825);
FORCEADD Q_CAP..1
(8375 4150);
FORCEPROP 1 LAST LOCATION PC130_3
J 0
(8425 4275);
DISPLAY 0.489362 (8425 4275);
PAINT SKYBLUE (8425 4275);
FORCEPROP 0 LAST $SEC 1
J 0
(8425 4325);
DISPLAY 0.680851 (8425 4325);
PAINT MONO (8425 4325);
DISPLAY INVISIBLE (8425 4325);
FORCEPROP 0 LAST CDS_SEC 1
J 0
(8425 4325);
DISPLAY 1.021277 (8425 4325);
DISPLAY INVISIBLE (8425 4325);
FORCEPROP 1 LASTPIN (8375 4250) $PN 1
J 0
(8385 4230);
DISPLAY 0.489362 (8385 4230);
PAINT MONO (8385 4230);
FORCEPROP 1 LASTPIN (8375 4050) $PN 2
J 0
(8385 4030);
DISPLAY 0.489362 (8385 4030);
PAINT MONO (8385 4030);
FORCEPROP 1 LAST MATERIAL X6S
J 0
(8425 4075);
DISPLAY 0.489362 (8425 4075);
PAINT SKYBLUE (8425 4075);
FORCEPROP 1 LAST TOLERANCE 20%
J 0
(8425 4125);
DISPLAY 0.489362 (8425 4125);
PAINT SKYBLUE (8425 4125);
FORCEPROP 1 LAST VALUE 22UF
J 0
(8425 4225);
DISPLAY 0.489362 (8425 4225);
PAINT SKYBLUE (8425 4225);
FORCEPROP 1 LAST VOLTAGE 4V
J 0
(8425 4175);
DISPLAY 0.489362 (8425 4175);
PAINT SKYBLUE (8425 4175);
FORCEPROP 1 LAST PACK_TYPE C0805
J 0
(8425 4025);
DISPLAY 0.489362 (8425 4025);
PAINT SKYBLUE (8425 4025);
FORCEPROP 2 LAST CDS_LIB pure_quanta
J 0
(8375 4150);
DISPLAY INVISIBLE (8375 4150);
FORCEPROP 1 LAST PATH I71
J 0
(8425 4300);
DISPLAY 0.978723 (8425 4300);
PAINT WHITE (8425 4300);
DISPLAY INVISIBLE (8425 4300);
FORCEPROP 1 LAST PART_NUMBER CH622KMEA03
J 0
(8425 3975);
DISPLAY 0.489362 (8425 3975);
PAINT SKYBLUE (8425 3975);
DISPLAY INVISIBLE (8425 3975);
FORCEADD VCC_CORE..1
(8375 4450);
FORCEPROP 3 LASTPIN (8375 4400) SIG_NAME PVDDCR_CPU1_P0\g
J 0
(8385 4410);
DISPLAY 0.659574 (8385 4410);
PAINT MONO (8385 4410);
DISPLAY INVISIBLE (8385 4410);
FORCEPROP 1 LAST HDL_POWER PVDDCR_CPU1_P0
J 1
(8375 4500);
DISPLAY 0.489362 (8375 4500);
PAINT GREEN (8375 4500);
FORCEPROP 2 LAST CDS_LIB pure_quanta_power
J 0
(8375 4450);
DISPLAY INVISIBLE (8375 4450);
FORCEPROP 1 LAST PATH I72
J 0
(8425 4475);
DISPLAY 0.872340 (8425 4475);
PAINT AQUA (8425 4475);
DISPLAY INVISIBLE (8425 4475);
FORCEADD OFFPAGE..5
(1800 1025);
FORCEPROP 2 LAST $XR3 200 
J 0
(1545 953);
DISPLAY 0.638298 (1545 953);
PAINT MONO (1545 953);
FORCEPROP 2 LAST $XR2 203 
J 0
(1545 1061);
DISPLAY 0.638298 (1545 1061);
PAINT MONO (1545 1061);
FORCEPROP 2 LAST $XR1 202 
J 0
(1545 989);
DISPLAY 0.638298 (1545 989);
PAINT MONO (1545 989);
FORCEPROP 2 LAST $XR0 201 
J 0
(1545 1025);
DISPLAY 0.638298 (1545 1025);
PAINT MONO (1545 1025);
FORCEPROP 2 LAST CDS_LIB standard
J 0
(1800 1025);
DISPLAY INVISIBLE (1800 1025);
FORCEPROP 1 LAST OFFPAGE TRUE
J 0
(2125 900);
DISPLAY 0.872340 (2125 900);
PAINT GREEN (2125 900);
DISPLAY INVISIBLE (2125 900);
FORCEPROP 1 LAST COMMENT_BODY TRUE
J 0
(1900 950);
DISPLAY 0.872340 (1900 950);
PAINT GREEN (1900 950);
DISPLAY INVISIBLE (1900 950);
FORCEPROP 2 LAST PATH I8
J 0
(1550 1150);
DISPLAY 0.680851 (1550 1150);
DISPLAY INVISIBLE (1550 1150);
FORCEADD OFFPAGE..1
(1800 1425);
FORCEPROP 2 LAST $XR5 206 
J 0
(948 1425);
DISPLAY 0.638298 (948 1425);
PAINT MONO (948 1425);
FORCEPROP 2 LAST $XR4 205 
J 0
(1068 1425);
DISPLAY 0.638298 (1068 1425);
PAINT MONO (1068 1425);
FORCEPROP 2 LAST $XR3 203 
J 0
(1188 1425);
DISPLAY 0.638298 (1188 1425);
PAINT MONO (1188 1425);
FORCEPROP 2 LAST $XR2 202 
J 0
(1308 1425);
DISPLAY 0.638298 (1308 1425);
PAINT MONO (1308 1425);
FORCEPROP 2 LAST $XR1 201 
J 0
(1428 1425);
DISPLAY 0.638298 (1428 1425);
PAINT MONO (1428 1425);
FORCEPROP 2 LAST $XR0 200 
J 0
(1548 1425);
DISPLAY 0.638298 (1548 1425);
PAINT MONO (1548 1425);
FORCEPROP 2 LAST CDS_LIB standard
J 0
(1800 1425);
DISPLAY INVISIBLE (1800 1425);
FORCEPROP 1 LAST OFFPAGE TRUE
J 0
(2125 1300);
DISPLAY 0.872340 (2125 1300);
PAINT GREEN (2125 1300);
DISPLAY INVISIBLE (2125 1300);
FORCEPROP 1 LAST COMMENT_BODY TRUE
J 0
(1925 1325);
DISPLAY 0.872340 (1925 1325);
PAINT GREEN (1925 1325);
DISPLAY INVISIBLE (1925 1325);
FORCEPROP 2 LAST PATH I9
J 0
(1550 1475);
DISPLAY 0.680851 (1550 1475);
DISPLAY INVISIBLE (1550 1475);
FORCEADD QUANTA_TITLE_BLOCK_C..1
(9450 25);
FORCEPROP 0 LAST CDS_CON_LAST_MODIFIED Thu Sep 14 16:12:19 2023
J 0
(7565 40);
DISPLAY INVISIBLE (7565 40);
FORCEPROP 1 LAST CUSTOM_TXT_CDS <CON_LAST_MODIFIED>
J 0
(7565 40);
DISPLAY 0.978723 (7565 40);
FORCEPROP 2 LAST CUSTOM_TXT_CDS <XR_PAGE_TITLE>
J 0
(1560 5275);
DISPLAY 0.638298 (1560 5275);
PAINT PINK (1560 5275);
DISPLAY INVISIBLE (1560 5275);
FORCEPROP 1 LAST CUSTOM_TXT_CDS <NAME_2>
J 0
(6275 75);
FORCEPROP 1 LAST CUSTOM_TXT_CDS <NAME_1>
J 0
(6275 200);
FORCEPROP 1 LAST CUSTOM_TXT_CDS <Q_NUMBER>
J 0
(8047 128);
DISPLAY 1.212766 (8047 128);
FORCEPROP 1 LAST CUSTOM_TXT_CDS <Q_PROJ>
J 0
(7068 127);
DISPLAY 1.212766 (7068 127);
FORCEPROP 1 LAST CUSTOM_TXT_CDS <Q_REV>
J 0
(9266 128);
DISPLAY 1.212766 (9266 128);
FORCEPROP 1 LAST CUSTOM_TXT_CDS <CON_PAGE_NUM> OF <CON_TOTAL_PAGES>
J 0
(9004 43);
DISPLAY 0.978723 (9004 43);
FORCEPROP 1 LAST Q_TITLE PVDDCR_CPU1_P0 VR PHASE 3&4
J 0
(150 75);
DISPLAY 2.446809 (150 75);
PAINT GREEN (150 75);
FORCEPROP 1 LAST CDS_LMAN_SYM_OUTLINE -9475,6775,100,-125
J 0
(9450 25);
DISPLAY 0.468085 (9450 25);
PAINT GREEN (9450 25);
DISPLAY INVISIBLE (9450 25);
FORCEPROP 2 LAST CDS_LIB pure_quanta
J 0
(9450 25);
DISPLAY INVISIBLE (9450 25);
FORCEPROP 2 LAST PAGE_BORDER TRUE
J 0
(1560 5275);
DISPLAY 0.638298 (1560 5275);
PAINT PINK (1560 5275);
DISPLAY INVISIBLE (1560 5275);
FORCEPROP 2 LAST CDS_XR_PAGE_TITLE CR-202 : @T6G_MB_LIB.T6G(SCH_1):PAGE202
J 0
(1560 5275);
DISPLAY 0.638298 (1560 5275);
PAINT PINK (1560 5275);
DISPLAY INVISIBLE (1560 5275);
FORCEPROP 1 LAST Q_DEPT BU9
J 1
(5687 74);
DISPLAY 1.957447 (5687 74);
PAINT GREEN (5687 74);
DISPLAY INVISIBLE (5687 74);
FORCEPROP 1 LAST COMMENT_BODY TRUE
J 0
(9462 12);
DISPLAY 0.978723 (9462 12);
PAINT GREEN (9462 12);
DISPLAY INVISIBLE (9462 12);
FORCEADD DNS..1
(4675 4150);
PAINT RED (4675 4150);
FORCEPROP 2 LAST CDS_LIB mstr_misc
J 0
(4675 4150);
DISPLAY INVISIBLE (4675 4150);
FORCEPROP 1 LAST COMMENT_BODY TRUE
R 1
J 0
(4750 3925);
DISPLAY 0.872340 (4750 3925);
PAINT GREEN (4750 3925);
DISPLAY INVISIBLE (4750 3925);
FORCEADD DNS..1
(4675 3600);
PAINT RED (4675 3600);
FORCEPROP 2 LAST CDS_LIB mstr_misc
J 0
(4675 3600);
DISPLAY INVISIBLE (4675 3600);
FORCEPROP 1 LAST COMMENT_BODY TRUE
R 1
J 0
(4750 3375);
DISPLAY 0.872340 (4750 3375);
PAINT GREEN (4750 3375);
DISPLAY INVISIBLE (4750 3375);
FORCEADD DNS..1
(4625 1350);
PAINT RED (4625 1350);
FORCEPROP 2 LAST CDS_LIB mstr_misc
J 0
(4625 1350);
DISPLAY INVISIBLE (4625 1350);
FORCEPROP 1 LAST COMMENT_BODY TRUE
R 1
J 0
(4700 1125);
DISPLAY 0.872340 (4700 1125);
PAINT GREEN (4700 1125);
DISPLAY INVISIBLE (4700 1125);
FORCEADD DNS..1
(4625 825);
PAINT RED (4625 825);
FORCEPROP 2 LAST CDS_LIB mstr_misc
J 0
(4625 825);
DISPLAY INVISIBLE (4625 825);
FORCEPROP 1 LAST COMMENT_BODY TRUE
R 1
J 0
(4700 600);
DISPLAY 0.872340 (4700 600);
PAINT GREEN (4700 600);
DISPLAY INVISIBLE (4700 600);
FORCEADD DNS..1
(1350 3825);
PAINT RED (1350 3825);
FORCEPROP 2 LAST CDS_LIB mstr_misc
J 0
(1350 3825);
PAINT MONO (1350 3825);
DISPLAY INVISIBLE (1350 3825);
FORCEPROP 1 LAST COMMENT_BODY TRUE
R 1
J 0
(1425 3600);
DISPLAY 0.872340 (1425 3600);
PAINT GREEN (1425 3600);
DISPLAY INVISIBLE (1425 3600);
FORCEADD DNS..1
(1325 1000);
PAINT RED (1325 1000);
FORCEPROP 2 LAST CDS_LIB mstr_misc
J 0
(1325 1000);
PAINT MONO (1325 1000);
DISPLAY INVISIBLE (1325 1000);
FORCEPROP 1 LAST COMMENT_BODY TRUE
R 1
J 0
(1400 775);
DISPLAY 0.872340 (1400 775);
PAINT GREEN (1400 775);
DISPLAY INVISIBLE (1400 775);
WIRE 16 -1 (825 1000)(825 1050);
WIRE 16 -1 (850 3825)(850 3875);
WIRE 16 -1 (1825 2450)(1825 2325);
WIRE 16 -1 (1350 3750)(1350 3675);
WIRE 16 -1 (1650 4700)(1650 4650);
WIRE 16 -1 (1325 925)(1325 850);
WIRE 16 -1 (2000 5275)(2000 5150);
WIRE 16 -1 (4650 725)(4650 650);
WIRE 16 -1 (4700 3500)(4700 3425);
WIRE 16 -1 (1475 1875)(1475 1825);
WIRE 16 -1 (5625 2325)(5625 2175);
WIRE 16 -1 (5625 2100)(5625 2175);
WIRE 16 -1 (5250 2175)(5625 2175);
WIRE 16 -1 (5250 2325)(5250 2175);
WIRE 16 -1 (4850 2175)(5250 2175);
WIRE 16 -1 (4850 2325)(4850 2175);
WIRE 16 -1 (4850 2175)(4450 2175);
WIRE 16 -1 (4450 2325)(4450 2175);
WIRE 16 -1 (4050 2175)(4450 2175);
WIRE 16 -1 (4050 2350)(4050 2175);
WIRE 16 -1 (4450 4100)(4450 3250);
WIRE 16 -1 (3675 4100)(4450 4100);
FORCEPROP 2 LAST SIG_NAME PVDDCR_CPU1_P0_VOS3
J 0
(3765 4125);
DISPLAY 0.489362 (3765 4125);
FORCEPROP 2 LASTPROP $XRERR UNIQUE?
J 0
(3525 4125);
DISPLAY 0.638298 (3525 4125);
PAINT MONO (3525 4125);
DISPLAY INVISIBLE (3525 4125);
WIRE 16 -1 (4450 3250)(5750 3250);
WIRE 16 -1 (4700 4350)(6075 4350);
WIRE 16 -1 (4700 4250)(4700 4350);
WIRE 16 -1 (4700 4350)(3675 4350);
FORCEPROP 2 LAST SIG_NAME SW_PVDDCR_CPU1_P0_SW3
J 0
(3865 4360);
DISPLAY 0.489362 (3865 4360);
FORCEPROP 2 LASTPROP $XRERR UNIQUE?
J 0
(3625 4360);
DISPLAY 0.638298 (3625 4360);
PAINT MONO (3625 4360);
DISPLAY INVISIBLE (3625 4360);
WIRE 16 -1 (5250 4450)(5250 4475);
WIRE 16 -1 (3675 4450)(5250 4450);
FORCEPROP 2 LAST SIG_NAME SW_PVDDCR_CPU1_P0_BOOTR3
J 0
(3865 4460);
DISPLAY 0.489362 (3865 4460);
FORCEPROP 2 LASTPROP $XRERR UNIQUE?
J 0
(3625 4460);
DISPLAY 0.638298 (3625 4460);
PAINT MONO (3625 4460);
DISPLAY INVISIBLE (3625 4460);
WIRE 16 -1 (4100 5200)(4100 5025);
WIRE 16 -1 (4100 5025)(4500 5025);
WIRE 16 -1 (4500 5175)(4500 5025);
WIRE 16 -1 (4900 5025)(4500 5025);
WIRE 16 -1 (4900 5025)(5300 5025);
WIRE 16 -1 (4900 5175)(4900 5025);
WIRE 16 -1 (5300 5175)(5300 5025);
WIRE 16 -1 (5300 5025)(5675 5025);
WIRE 16 -1 (5675 5175)(5675 5025);
WIRE 16 -1 (5675 4975)(5675 5025);
WIRE 16 -1 (3675 4950)(3850 4950);
WIRE 16 -1 (3850 4950)(3850 5000);
WIRE 16 -1 (3850 5525)(3850 5000);
WIRE 16 -1 (3675 5000)(3850 5000);
WIRE 16 -1 (4100 5525)(3850 5525);
WIRE 16 -1 (4500 5525)(4100 5525);
WIRE 16 -1 (4100 5400)(4100 5525);
WIRE 16 -1 (4500 5525)(4900 5525);
WIRE 16 -1 (4500 5375)(4500 5525);
WIRE 16 -1 (4900 5525)(5300 5525);
WIRE 16 -1 (4900 5525)(4900 5375);
WIRE 16 -1 (5300 5525)(5675 5525);
WIRE 16 -1 (5300 5375)(5300 5525);
WIRE 16 -1 (5675 5575)(5675 5525);
WIRE 16 -1 (5675 5375)(5675 5525);
WIRE 16 -1 (5250 4700)(5250 4675);
WIRE 16 -1 (4625 4700)(5250 4700);
FORCEPROP 2 LAST SIG_NAME SW_PVDDCR_CPU1_P0_BOOT3_R
J 0
(4740 4710);
DISPLAY 0.489362 (4740 4710);
FORCEPROP 2 LASTPROP $XRERR UNIQUE?
J 0
(4500 4710);
DISPLAY 0.638298 (4500 4710);
PAINT MONO (4500 4710);
DISPLAY INVISIBLE (4500 4710);
WIRE 16 -1 (3650 2125)(3825 2125);
WIRE 16 -1 (3825 2125)(3825 2175);
WIRE 16 -1 (3825 2675)(3825 2175);
WIRE 16 -1 (3650 2175)(3825 2175);
WIRE 16 -1 (4050 2675)(3825 2675);
WIRE 16 -1 (4450 2675)(4050 2675);
WIRE 16 -1 (4050 2550)(4050 2675);
WIRE 16 -1 (4450 2675)(4850 2675);
WIRE 16 -1 (4450 2525)(4450 2675);
WIRE 16 -1 (4850 2675)(5250 2675);
WIRE 16 -1 (4850 2675)(4850 2525);
WIRE 16 -1 (5250 2675)(5625 2675);
WIRE 16 -1 (5250 2525)(5250 2675);
WIRE 16 -1 (5625 2725)(5625 2675);
WIRE 16 -1 (5625 2525)(5625 2675);
WIRE 16 -1 (3675 4700)(4425 4700);
FORCEPROP 2 LAST SIG_NAME SW_PVDDCR_CPU1_P0_BOOT3
J 0
(3840 4710);
DISPLAY 0.489362 (3840 4710);
FORCEPROP 2 LASTPROP $XRERR UNIQUE?
J 0
(3600 4710);
DISPLAY 0.638298 (3600 4710);
PAINT MONO (3600 4710);
DISPLAY INVISIBLE (3600 4710);
WIRE 16 -1 (3650 1875)(4400 1875);
FORCEPROP 2 LAST SIG_NAME SW_PVDDCR_CPU1_P0_BOOT4
J 0
(3840 1885);
DISPLAY 0.489362 (3840 1885);
FORCEPROP 2 LASTPROP $XRERR UNIQUE?
J 0
(3600 1885);
DISPLAY 0.638298 (3600 1885);
PAINT MONO (3600 1885);
DISPLAY INVISIBLE (3600 1885);
WIRE 16 -1 (5225 1875)(5225 1850);
WIRE 16 -1 (4600 1875)(5225 1875);
FORCEPROP 2 LAST SIG_NAME SW_PVDDCR_CPU1_P0_BOOT4_R
J 0
(4665 1885);
DISPLAY 0.489362 (4665 1885);
FORCEPROP 2 LASTPROP $XRERR UNIQUE?
J 0
(4425 1885);
DISPLAY 0.638298 (4425 1885);
PAINT MONO (4425 1885);
DISPLAY INVISIBLE (4425 1885);
WIRE 16 -1 (4700 4050)(4700 3700);
FORCEPROP 2 LAST SIG_NAME SW_PVDDCR_CPU1_P0_SW3_RC
J 0
(4740 3860);
DISPLAY 0.489362 (4740 3860);
FORCEPROP 2 LASTPROP $XRERR UNIQUE?
J 0
(4500 3860);
DISPLAY 0.638298 (4500 3860);
PAINT MONO (4500 3860);
DISPLAY INVISIBLE (4500 3860);
WIRE 16 -1 (2800 2175)(2725 2175);
WIRE 16 -1 (2725 2175)(2725 2750);
WIRE 16 -1 (2725 2750)(1825 2750);
WIRE 16 -1 (1825 2650)(1825 2750);
WIRE 16 -1 (1825 2750)(1475 2750);
WIRE 16 -1 (1475 2900)(1475 2750);
WIRE 16 -1 (1475 2625)(1475 2750);
WIRE 16 -1 (3650 1075)(3900 1075);
WIRE 16 -1 (3900 1075)(3900 1025);
WIRE 16 -1 (3650 1025)(3900 1025);
WIRE 16 -1 (3900 1025)(3900 975);
WIRE 16 -1 (3900 975)(3900 925);
WIRE 16 -1 (3650 975)(3900 975);
WIRE 16 -1 (3650 925)(3900 925);
WIRE 16 -1 (3900 925)(3900 850);
WIRE 16 -1 (3675 3800)(3925 3800);
WIRE 16 -1 (3925 3850)(3925 3800);
WIRE 16 -1 (3925 3800)(3925 3750);
WIRE 16 -1 (3675 3750)(3925 3750);
WIRE 16 -1 (3925 3750)(3925 3675);
WIRE 16 -1 (3925 3900)(3925 3850);
WIRE 16 -1 (3675 3850)(3925 3850);
WIRE 16 -1 (3675 3900)(3925 3900);
WIRE 16 -1 (2825 5000)(2325 5000);
WIRE 16 -1 (2325 5000)(2325 5575);
WIRE 16 -1 (2325 5575)(2000 5575);
WIRE 16 -1 (2000 5475)(2000 5575);
WIRE 16 -1 (2000 5575)(1650 5575);
WIRE 16 -1 (1650 5725)(1650 5575);
WIRE 16 -1 (1650 5450)(1650 5575);
WIRE 16 -1 (6550 1275)(6975 1275);
WIRE 16 -1 (6975 1125)(6975 1275);
WIRE 16 -1 (7925 1100)(7925 1225);
WIRE 16 -1 (7925 1100)(7500 1100);
WIRE 16 -1 (7925 950)(7925 1100);
WIRE 16 -1 (7500 1100)(7500 1225);
WIRE 16 -1 (7250 525)(7250 1525);
WIRE 16 -1 (7250 525)(5950 525);
WIRE 16 -1 (7250 1525)(7500 1525);
WIRE 16 -1 (6550 1525)(7250 1525);
WIRE 16 -1 (7500 1525)(7925 1525);
WIRE 16 -1 (7500 1525)(7500 1425);
WIRE 16 -1 (7925 1575)(7925 1525);
WIRE 16 -1 (7925 1525)(7925 1425);
WIRE 16 -1 (8375 4050)(8375 3925);
WIRE 16 -1 (8375 3875)(8375 3925);
WIRE 16 -1 (8375 3925)(7950 3925);
WIRE 16 -1 (7950 3925)(7950 4050);
WIRE 16 -1 (5950 3250)(7725 3250);
WIRE 16 -1 (7725 3250)(7725 4350);
WIRE 16 -1 (7950 4350)(7725 4350);
WIRE 16 -1 (7725 4350)(6875 4350);
WIRE 16 -1 (7950 4350)(8375 4350);
WIRE 16 -1 (7950 4350)(7950 4250);
WIRE 16 -1 (8375 4400)(8375 4350);
WIRE 16 -1 (8375 4250)(8375 4350);
WIRE 16 -1 (1475 2150)(2050 2150);
WIRE 16 -1 (1475 2425)(1475 2150);
WIRE 16 -1 (1475 2150)(1475 2075);
WIRE 16 -1 (2050 2150)(2050 1875);
WIRE 16 -1 (2700 1875)(2050 1875);
FORCEPROP 2 LAST SIG_NAME PVDDCR_CPU1_P0_VCC4
J 0
(2165 1885);
DISPLAY 0.489362 (2165 1885);
FORCEPROP 2 LASTPROP $XRERR UNIQUE?
J 0
(1925 1885);
DISPLAY 0.638298 (1925 1885);
PAINT MONO (1925 1885);
DISPLAY INVISIBLE (1925 1885);
WIRE 16 -1 (2800 1875)(2700 1875);
WIRE 16 -1 (2700 1675)(2700 1875);
WIRE 16 -1 (2800 1675)(2700 1675);
WIRE 16 -1 (4650 1525)(5750 1525);
WIRE 16 -1 (4650 1525)(4650 1450);
WIRE 16 -1 (3650 1525)(4650 1525);
FORCEPROP 2 LAST SIG_NAME SW_PVDDCR_CPU1_P0_SW4
J 0
(3840 1535);
DISPLAY 0.489362 (3840 1535);
FORCEPROP 2 LASTPROP $XRERR UNIQUE?
J 0
(3600 1535);
DISPLAY 0.638298 (3600 1535);
PAINT MONO (3600 1535);
DISPLAY INVISIBLE (3600 1535);
WIRE 16 -1 (1650 4900)(1650 5000);
WIRE 16 -1 (1650 5000)(2100 5000);
WIRE 16 -1 (1650 5250)(1650 5000);
WIRE 16 -1 (2100 5000)(2100 4700);
WIRE 16 -1 (2725 4700)(2100 4700);
FORCEPROP 2 LAST SIG_NAME PVDDCR_CPU1_P0_VCC3
J 0
(2190 4710);
DISPLAY 0.489362 (2190 4710);
FORCEPROP 2 LASTPROP $XRERR UNIQUE?
J 0
(1950 4710);
DISPLAY 0.638298 (1950 4710);
PAINT MONO (1950 4710);
DISPLAY INVISIBLE (1950 4710);
WIRE 16 -1 (2725 4700)(2825 4700);
WIRE 16 -1 (2725 4500)(2725 4700);
WIRE 16 -1 (2825 4500)(2725 4500);
WIRE 16 -1 (6875 4100)(7375 4100);
FORCEPROP 2 LAST SIG_NAME IND_CPU1_P0_CPL3
J 0
(6965 4110);
DISPLAY 0.489362 (6965 4110);
WIRE 16 -1 (5300 4100)(6075 4100);
FORCEPROP 2 LAST SIG_NAME IND_CPU1_P0_CPL2
J 0
(5365 4110);
DISPLAY 0.489362 (5365 4110);
WIRE 16 -1 (5275 1275)(5750 1275);
FORCEPROP 2 LAST SIG_NAME IND_CPU1_P0_CPL3
J 0
(5340 1285);
DISPLAY 0.489362 (5340 1285);
WIRE 16 -1 (4650 1250)(4650 925);
FORCEPROP 2 LAST SIG_NAME SW_PVDDCR_CPU1_P0_SW4_RC
J 0
(4690 1035);
DISPLAY 0.489362 (4690 1035);
FORCEPROP 2 LASTPROP $XRERR UNIQUE?
J 0
(4450 1035);
DISPLAY 0.638298 (4450 1035);
PAINT MONO (4450 1035);
DISPLAY INVISIBLE (4450 1035);
WIRE 16 -1 (4425 525)(5750 525);
WIRE 16 -1 (4425 1275)(4425 525);
WIRE 16 -1 (3650 1275)(4425 1275);
FORCEPROP 2 LAST SIG_NAME PVDDCR_CPU1_P0_VOS4
J 0
(3765 1300);
DISPLAY 0.489362 (3765 1300);
FORCEPROP 2 LASTPROP $XRERR UNIQUE?
J 0
(3525 1300);
DISPLAY 0.638298 (3525 1300);
PAINT MONO (3525 1300);
DISPLAY INVISIBLE (3525 1300);
WIRE 16 -1 (4200 4000)(3675 4000);
FORCEPROP 2 LAST SIG_NAME NC_PVDDCR_CPU1_P0_GL2_3
J 0
(3765 4010);
DISPLAY 0.489362 (3765 4010);
FORCEPROP 2 LASTPROP $XRERR UNIQUE?
J 0
(4230 4000);
DISPLAY 0.638298 (4230 4000);
PAINT MONO (4230 4000);
DISPLAY INVISIBLE (4230 4000);
WIRE 16 -1 (4200 4050)(3675 4050);
FORCEPROP 2 LAST SIG_NAME NC_PVDDCR_CPU1_P0_GL1_3
J 0
(3765 4060);
DISPLAY 0.489362 (3765 4060);
FORCEPROP 2 LASTPROP $XRERR UNIQUE?
J 0
(4230 4050);
DISPLAY 0.638298 (4230 4050);
PAINT MONO (4230 4050);
DISPLAY INVISIBLE (4230 4050);
WIRE 16 -1 (3650 1225)(4225 1225);
FORCEPROP 2 LAST SIG_NAME NC_PVDDCR_CPU1_P0_GL1_4
J 0
(3765 1235);
DISPLAY 0.489362 (3765 1235);
FORCEPROP 2 LASTPROP $XRERR UNIQUE?
J 0
(4255 1225);
DISPLAY 0.638298 (4255 1225);
PAINT MONO (4255 1225);
DISPLAY INVISIBLE (4255 1225);
WIRE 16 -1 (3650 1175)(4225 1175);
FORCEPROP 2 LAST SIG_NAME NC_PVDDCR_CPU1_P0_GL2_4
J 0
(3765 1185);
DISPLAY 0.489362 (3765 1185);
FORCEPROP 2 LASTPROP $XRERR UNIQUE?
J 0
(4255 1175);
DISPLAY 0.638298 (4255 1175);
PAINT MONO (4255 1175);
DISPLAY INVISIBLE (4255 1175);
WIRE 16 -1 (5225 1625)(5225 1650);
WIRE 16 -1 (3650 1625)(5225 1625);
FORCEPROP 2 LAST SIG_NAME SW_PVDDCR_CPU1_P0_BOOTR4
J 0
(3840 1635);
DISPLAY 0.489362 (3840 1635);
FORCEPROP 2 LASTPROP $XRERR UNIQUE?
J 0
(3600 1635);
DISPLAY 0.638298 (3600 1635);
PAINT MONO (3600 1635);
DISPLAY INVISIBLE (3600 1635);
WIRE 16 -1 (2825 4100)(2450 4100);
FORCEPROP 2 LAST SIG_NAME NC_PVDDCR_CPU1_P0_DNC3
J 0
(2255 4110);
DISPLAY 0.489362 (2255 4110);
FORCEPROP 2 LASTPROP $XRERR UNIQUE?
J 0
(2210 4100);
DISPLAY 0.638298 (2210 4100);
PAINT MONO (2210 4100);
DISPLAY INVISIBLE (2210 4100);
WIRE 16 -1 (2825 4350)(1875 4350);
FORCEPROP 2 LAST SIG_NAME PVDDCR_CPU1_P0_IMON3
J 0
(1990 4360);
DISPLAY 0.489362 (1990 4360);
WIRE 16 -1 (2725 4250)(2725 4175);
FORCEPROP 0 LAST CDS_PHYS_NET_NAME PVDDCR_CPU1_P0_VCCS
J 0
(2725 4200);
PAINT MONO (2725 4200);
DISPLAY INVISIBLE (2725 4200);
WIRE 16 -1 (2725 4250)(2825 4250);
WIRE 16 -1 (1875 4250)(2725 4250);
FORCEPROP 2 LAST SIG_NAME PVDDCR_CPU1_P0_VCCS
J 0
(1990 4260);
DISPLAY 0.489362 (1990 4260);
WIRE 16 -1 (2725 4175)(850 4175);
WIRE 16 -1 (850 4175)(850 4075);
WIRE 16 -1 (1350 4050)(2825 4050);
FORCEPROP 2 LAST SIG_NAME PVDDCR_CPU1_P0_LSET3
J 0
(1990 4060);
DISPLAY 0.489362 (1990 4060);
FORCEPROP 2 LASTPROP $XRERR UNIQUE?
J 0
(1750 4060);
DISPLAY 0.638298 (1750 4060);
PAINT MONO (1750 4060);
DISPLAY INVISIBLE (1750 4060);
WIRE 16 -1 (1350 4050)(1350 3950);
WIRE 16 -1 (2800 1275)(2425 1275);
FORCEPROP 2 LAST SIG_NAME NC_PVDDCR_CPU1_P0_DNC4
J 0
(2230 1285);
DISPLAY 0.489362 (2230 1285);
FORCEPROP 2 LASTPROP $XRERR UNIQUE?
J 0
(2185 1275);
DISPLAY 0.638298 (2185 1275);
PAINT MONO (2185 1275);
DISPLAY INVISIBLE (2185 1275);
WIRE 16 -1 (2800 1525)(1850 1525);
FORCEPROP 2 LAST SIG_NAME PVDDCR_CPU1_P0_IMON4
J 0
(1965 1535);
DISPLAY 0.489362 (1965 1535);
WIRE 16 -1 (2825 3850)(1875 3850);
FORCEPROP 2 LAST SIG_NAME PVDDCR_CPU1_P0_TEMP0
J 0
(1990 3860);
DISPLAY 0.489362 (1990 3860);
WIRE 16 -1 (2825 3750)(1875 3750);
FORCEPROP 2 LAST SIG_NAME PVDDCR_CPU1_P0_PWM3
J 0
(1990 3760);
DISPLAY 0.489362 (1990 3760);
WIRE 16 -1 (2700 1425)(2700 1350);
FORCEPROP 0 LAST CDS_PHYS_NET_NAME PVDDCR_CPU1_P0_VCCS
J 0
(2700 1375);
PAINT MONO (2700 1375);
DISPLAY INVISIBLE (2700 1375);
WIRE 16 -1 (2700 1425)(2800 1425);
WIRE 16 -1 (1850 1425)(2700 1425);
FORCEPROP 2 LAST SIG_NAME PVDDCR_CPU1_P0_VCCS
J 0
(1965 1435);
DISPLAY 0.489362 (1965 1435);
WIRE 16 -1 (2700 1350)(825 1350);
WIRE 16 -1 (825 1350)(825 1250);
WIRE 16 -1 (2800 1025)(1850 1025);
FORCEPROP 2 LAST SIG_NAME PVDDCR_CPU1_P0_TEMP0
J 0
(1965 1035);
DISPLAY 0.489362 (1965 1035);
WIRE 16 -1 (2800 925)(1850 925);
FORCEPROP 2 LAST SIG_NAME PVDDCR_CPU1_P0_PWM4
J 0
(1965 935);
DISPLAY 0.489362 (1965 935);
WIRE 16 -1 (1325 1225)(2800 1225);
FORCEPROP 2 LAST SIG_NAME PVDDCR_CPU1_P0_LSET4
J 0
(1965 1235);
DISPLAY 0.489362 (1965 1235);
FORCEPROP 2 LASTPROP $XRERR UNIQUE?
J 0
(1725 1235);
DISPLAY 0.638298 (1725 1235);
PAINT MONO (1725 1235);
DISPLAY INVISIBLE (1725 1235);
WIRE 16 -1 (1325 1225)(1325 1125);
DOT 1 (8375 4350);
DOT 1 (8375 3925);
DOT 1 (7725 4350);
DOT 1 (7950 4350);
DOT 1 (5675 5525);
DOT 1 (5300 5525);
DOT 1 (5675 5025);
DOT 1 (5300 5025);
DOT 1 (4900 5525);
DOT 1 (4500 5525);
DOT 1 (4900 5025);
DOT 1 (4700 4350);
DOT 1 (4500 5025);
DOT 1 (7925 1525);
DOT 1 (7925 1100);
DOT 1 (7500 1525);
DOT 1 (7250 1525);
DOT 1 (5625 2675);
DOT 1 (5250 2675);
DOT 1 (5625 2175);
DOT 1 (5250 2175);
DOT 1 (4850 2675);
DOT 1 (4850 2175);
DOT 1 (4450 2675);
DOT 1 (4450 2175);
DOT 1 (4650 1525);
DOT 1 (4100 5525);
DOT 1 (3850 5000);
DOT 1 (2725 4700);
DOT 1 (2725 4250);
DOT 1 (2000 5575);
DOT 1 (1650 5575);
DOT 1 (1650 5000);
DOT 1 (3925 3800);
DOT 1 (3925 3850);
DOT 1 (3925 3750);
DOT 1 (4050 2675);
DOT 1 (3825 2175);
DOT 1 (3900 1025);
DOT 1 (3900 975);
DOT 1 (3900 925);
DOT 1 (2700 1875);
DOT 1 (2700 1425);
DOT 1 (1825 2750);
DOT 1 (1475 2750);
DOT 1 (1475 2150);
FORCENOTE
PGL6303.151HLT
(6900 4675) 0;
DISPLAY LEFT (6900 4675);
DISPLAY 0.638298 (6900 4675);
PAINT WHITE (6900 4675);
FORCENOTE
ISAT:70A@100C
(6900 4625) 0;
DISPLAY LEFT (6900 4625);
DISPLAY 0.638298 (6900 4625);
PAINT WHITE (6900 4625);
FORCENOTE
DCR=1-4,0.105M OHM
(6900 4525) 0;
DISPLAY LEFT (6900 4525);
DISPLAY 0.638298 (6900 4525);
PAINT WHITE (6900 4525);
FORCENOTE
2ND=CV+15^0TZ01
(6900 4425) 0;
DISPLAY LEFT (6900 4425);
DISPLAY 0.638298 (6900 4425);
PAINT WHITE (6900 4425);
FORCENOTE
11.0*7.5*12.5
(6900 4575) 0;
DISPLAY LEFT (6900 4575);
DISPLAY 0.638298 (6900 4575);
PAINT WHITE (6900 4575);
FORCENOTE
DCR=2-3,0.27M OHM
(6900 4475) 0;
DISPLAY LEFT (6900 4475);
DISPLAY 0.638298 (6900 4475);
PAINT WHITE (6900 4475);
FORCENOTE
2ND=CV+15^0TZ01
(6575 1600) 0;
DISPLAY LEFT (6575 1600);
DISPLAY 0.638298 (6575 1600);
PAINT WHITE (6575 1600);
FORCENOTE
DCR=2-3,0.27M OHM
(6575 1650) 0;
DISPLAY LEFT (6575 1650);
DISPLAY 0.638298 (6575 1650);
PAINT WHITE (6575 1650);
FORCENOTE
DCR=1-4,0.105M OHM
(6575 1700) 0;
DISPLAY LEFT (6575 1700);
DISPLAY 0.638298 (6575 1700);
PAINT WHITE (6575 1700);
FORCENOTE
ISAT:70A@100C
(6575 1800) 0;
DISPLAY LEFT (6575 1800);
DISPLAY 0.638298 (6575 1800);
PAINT WHITE (6575 1800);
FORCENOTE
PGL6303.151HLT
(6575 1850) 0;
DISPLAY LEFT (6575 1850);
DISPLAY 0.638298 (6575 1850);
PAINT WHITE (6575 1850);
FORCENOTE
11.0*7.5*12.5
(6575 1750) 0;
DISPLAY LEFT (6575 1750);
DISPLAY 0.638298 (6575 1750);
PAINT WHITE (6575 1750);
FORCENOTE
PVDDCR_CPU1_P0_PHASE3
(2800 5725) 0;
DISPLAY LEFT (2800 5725);
DISPLAY 1.021277 (2800 5725);
PAINT WHITE (2800 5725);
FORCENOTE
PVDDCR_CPU1_P0_PHASE4
(2825 2850) 0;
DISPLAY LEFT (2825 2850);
DISPLAY 1.021277 (2825 2850);
PAINT WHITE (2825 2850);
QUIT
